FILE_TYPE = MACRO_DRAWING;
SET COLOR_WIRE YELLOW;
SET COLOR_PROP MONO;
SET COLOR_DOT WHITE;
SET COLOR_ARC YELLOW;
SET COLOR_BODY GREEN;
SET COLOR_NOTE MONO;
SET PROP_DISPLAY VALUE;
SET PAGE_NUMBER P34;
FORCEADD OFFPAGE..1
(-6500 2575);
FORCEPROP 2 LAST $XR0 68 
J 0
(-6751 2575);
DISPLAY 0.638298 (-6751 2575);
PAINT MONO (-6751 2575);
FORCEPROP 2 LAST CDS_LIB mstr_standard
J 0
(-6500 2575);
PAINT MONO (-6500 2575);
DISPLAY INVISIBLE (-6500 2575);
FORCEPROP 1 LAST OFFPAGE TRUE
J 0
(-6175 2450);
DISPLAY 1.170213 (-6175 2450);
PAINT GREEN (-6175 2450);
DISPLAY INVISIBLE (-6175 2450);
FORCEPROP 1 LAST COMMENT_BODY TRUE
J 0
(-6375 2475);
DISPLAY 1.170213 (-6375 2475);
PAINT GREEN (-6375 2475);
DISPLAY INVISIBLE (-6375 2475);
FORCEPROP 2 LAST PATH I1
J 0
(-6450 2650);
DISPLAY 1.021277 (-6450 2650);
PAINT ORANGE (-6450 2650);
DISPLAY INVISIBLE (-6450 2650);
FORCEADD TAP..1
R 2
(-5300 1925);
FORCEPROP 3 LASTPIN (-5250 1925) SIG_NAME UPI_CPU1_CPU0_P1P1_DN<12>
J 0
(-5240 1935);
DISPLAY 0.659574 (-5240 1935);
PAINT MONO (-5240 1935);
DISPLAY INVISIBLE (-5240 1935);
FORCEPROP 1 LASTPIN (-5250 1925) BN 12
J 2
(-5238 1933);
DISPLAY 0.617021 (-5238 1933);
PAINT PINK (-5238 1933);
FORCEPROP 2 LAST CDS_LIB mstr_standard
J 0
(-5300 1925);
PAINT MONO (-5300 1925);
DISPLAY INVISIBLE (-5300 1925);
FORCEPROP 1 LAST BODY_TYPE PLUMBING
J 2
(-5300 1975);
DISPLAY 1.446809 (-5300 1975);
PAINT GREEN (-5300 1975);
DISPLAY INVISIBLE (-5300 1975);
FORCEPROP 1 LAST HDL_TAP TRUE
J 2
(-5625 1800);
DISPLAY 1.446809 (-5625 1800);
PAINT GREEN (-5625 1800);
DISPLAY INVISIBLE (-5625 1800);
FORCEPROP 1 LAST PATH I10
J 2
(-5298 1925);
DISPLAY 0.872340 (-5298 1925);
PAINT GREEN (-5298 1925);
DISPLAY INVISIBLE (-5298 1925);
FORCEADD TAP..1
R 2
(-5300 1825);
FORCEPROP 3 LASTPIN (-5250 1825) SIG_NAME UPI_CPU1_CPU0_P1P1_DN<14>
J 0
(-5240 1835);
DISPLAY 0.659574 (-5240 1835);
PAINT MONO (-5240 1835);
DISPLAY INVISIBLE (-5240 1835);
FORCEPROP 1 LASTPIN (-5250 1825) BN 14
J 2
(-5238 1833);
DISPLAY 0.617021 (-5238 1833);
PAINT PINK (-5238 1833);
FORCEPROP 2 LAST CDS_LIB mstr_standard
J 0
(-5300 1825);
PAINT MONO (-5300 1825);
DISPLAY INVISIBLE (-5300 1825);
FORCEPROP 1 LAST BODY_TYPE PLUMBING
J 2
(-5300 1875);
DISPLAY 1.446809 (-5300 1875);
PAINT GREEN (-5300 1875);
DISPLAY INVISIBLE (-5300 1875);
FORCEPROP 1 LAST HDL_TAP TRUE
J 2
(-5625 1700);
DISPLAY 1.446809 (-5625 1700);
PAINT GREEN (-5625 1700);
DISPLAY INVISIBLE (-5625 1700);
FORCEPROP 1 LAST PATH I11
J 2
(-5298 1825);
DISPLAY 0.872340 (-5298 1825);
PAINT GREEN (-5298 1825);
DISPLAY INVISIBLE (-5298 1825);
FORCEADD TAP..1
R 2
(-5300 1975);
FORCEPROP 3 LASTPIN (-5250 1975) SIG_NAME UPI_CPU1_CPU0_P1P1_DN<11>
J 0
(-5240 1985);
DISPLAY 0.659574 (-5240 1985);
PAINT MONO (-5240 1985);
DISPLAY INVISIBLE (-5240 1985);
FORCEPROP 1 LASTPIN (-5250 1975) BN 11
J 2
(-5238 1983);
DISPLAY 0.617021 (-5238 1983);
PAINT PINK (-5238 1983);
FORCEPROP 2 LAST CDS_LIB mstr_standard
J 0
(-5300 1975);
PAINT MONO (-5300 1975);
DISPLAY INVISIBLE (-5300 1975);
FORCEPROP 1 LAST BODY_TYPE PLUMBING
J 2
(-5300 2025);
DISPLAY 1.446809 (-5300 2025);
PAINT GREEN (-5300 2025);
DISPLAY INVISIBLE (-5300 2025);
FORCEPROP 1 LAST HDL_TAP TRUE
J 2
(-5625 1850);
DISPLAY 1.446809 (-5625 1850);
PAINT GREEN (-5625 1850);
DISPLAY INVISIBLE (-5625 1850);
FORCEPROP 1 LAST PATH I12
J 2
(-5298 1975);
DISPLAY 0.872340 (-5298 1975);
PAINT GREEN (-5298 1975);
DISPLAY INVISIBLE (-5298 1975);
FORCEADD TAP..1
R 2
(-5300 2025);
FORCEPROP 3 LASTPIN (-5250 2025) SIG_NAME UPI_CPU1_CPU0_P1P1_DN<10>
J 0
(-5240 2035);
DISPLAY 0.659574 (-5240 2035);
PAINT MONO (-5240 2035);
DISPLAY INVISIBLE (-5240 2035);
FORCEPROP 1 LASTPIN (-5250 2025) BN 10
J 2
(-5238 2033);
DISPLAY 0.617021 (-5238 2033);
PAINT PINK (-5238 2033);
FORCEPROP 2 LAST CDS_LIB mstr_standard
J 0
(-5300 2025);
PAINT MONO (-5300 2025);
DISPLAY INVISIBLE (-5300 2025);
FORCEPROP 1 LAST BODY_TYPE PLUMBING
J 2
(-5300 2075);
DISPLAY 1.446809 (-5300 2075);
PAINT GREEN (-5300 2075);
DISPLAY INVISIBLE (-5300 2075);
FORCEPROP 1 LAST HDL_TAP TRUE
J 2
(-5625 1900);
DISPLAY 1.446809 (-5625 1900);
PAINT GREEN (-5625 1900);
DISPLAY INVISIBLE (-5625 1900);
FORCEPROP 1 LAST PATH I13
J 2
(-5298 2025);
DISPLAY 0.872340 (-5298 2025);
PAINT GREEN (-5298 2025);
DISPLAY INVISIBLE (-5298 2025);
FORCEADD TAP..1
R 2
(-5300 2075);
FORCEPROP 3 LASTPIN (-5250 2075) SIG_NAME UPI_CPU1_CPU0_P1P1_DN<9>
J 0
(-5240 2085);
DISPLAY 0.659574 (-5240 2085);
PAINT MONO (-5240 2085);
DISPLAY INVISIBLE (-5240 2085);
FORCEPROP 1 LASTPIN (-5250 2075) BN 9
J 2
(-5238 2083);
DISPLAY 0.617021 (-5238 2083);
PAINT PINK (-5238 2083);
FORCEPROP 2 LAST CDS_LIB mstr_standard
J 0
(-5300 2075);
PAINT MONO (-5300 2075);
DISPLAY INVISIBLE (-5300 2075);
FORCEPROP 1 LAST BODY_TYPE PLUMBING
J 2
(-5300 2125);
DISPLAY 1.446809 (-5300 2125);
PAINT GREEN (-5300 2125);
DISPLAY INVISIBLE (-5300 2125);
FORCEPROP 1 LAST HDL_TAP TRUE
J 2
(-5625 1950);
DISPLAY 1.446809 (-5625 1950);
PAINT GREEN (-5625 1950);
DISPLAY INVISIBLE (-5625 1950);
FORCEPROP 1 LAST PATH I14
J 2
(-5298 2075);
DISPLAY 0.872340 (-5298 2075);
PAINT GREEN (-5298 2075);
DISPLAY INVISIBLE (-5298 2075);
FORCEADD TAP..1
R 2
(-5300 2125);
FORCEPROP 3 LASTPIN (-5250 2125) SIG_NAME UPI_CPU1_CPU0_P1P1_DN<8>
J 0
(-5240 2135);
DISPLAY 0.659574 (-5240 2135);
PAINT MONO (-5240 2135);
DISPLAY INVISIBLE (-5240 2135);
FORCEPROP 1 LASTPIN (-5250 2125) BN 8
J 2
(-5238 2133);
DISPLAY 0.617021 (-5238 2133);
PAINT PINK (-5238 2133);
FORCEPROP 2 LAST CDS_LIB mstr_standard
J 0
(-5300 2125);
PAINT MONO (-5300 2125);
DISPLAY INVISIBLE (-5300 2125);
FORCEPROP 1 LAST BODY_TYPE PLUMBING
J 2
(-5300 2175);
DISPLAY 1.446809 (-5300 2175);
PAINT GREEN (-5300 2175);
DISPLAY INVISIBLE (-5300 2175);
FORCEPROP 1 LAST HDL_TAP TRUE
J 2
(-5625 2000);
DISPLAY 1.446809 (-5625 2000);
PAINT GREEN (-5625 2000);
DISPLAY INVISIBLE (-5625 2000);
FORCEPROP 1 LAST PATH I15
J 2
(-5298 2125);
DISPLAY 0.872340 (-5298 2125);
PAINT GREEN (-5298 2125);
DISPLAY INVISIBLE (-5298 2125);
FORCEADD TAP..1
R 2
(-5300 2175);
FORCEPROP 3 LASTPIN (-5250 2175) SIG_NAME UPI_CPU1_CPU0_P1P1_DN<7>
J 0
(-5240 2185);
DISPLAY 0.659574 (-5240 2185);
PAINT MONO (-5240 2185);
DISPLAY INVISIBLE (-5240 2185);
FORCEPROP 1 LASTPIN (-5250 2175) BN 7
J 2
(-5238 2183);
DISPLAY 0.617021 (-5238 2183);
PAINT PINK (-5238 2183);
FORCEPROP 2 LAST CDS_LIB mstr_standard
J 0
(-5300 2175);
PAINT MONO (-5300 2175);
DISPLAY INVISIBLE (-5300 2175);
FORCEPROP 1 LAST BODY_TYPE PLUMBING
J 2
(-5300 2225);
DISPLAY 1.446809 (-5300 2225);
PAINT GREEN (-5300 2225);
DISPLAY INVISIBLE (-5300 2225);
FORCEPROP 1 LAST HDL_TAP TRUE
J 2
(-5625 2050);
DISPLAY 1.446809 (-5625 2050);
PAINT GREEN (-5625 2050);
DISPLAY INVISIBLE (-5625 2050);
FORCEPROP 1 LAST PATH I16
J 2
(-5298 2175);
DISPLAY 0.872340 (-5298 2175);
PAINT GREEN (-5298 2175);
DISPLAY INVISIBLE (-5298 2175);
FORCEADD TAP..1
R 2
(-5300 2225);
FORCEPROP 3 LASTPIN (-5250 2225) SIG_NAME UPI_CPU1_CPU0_P1P1_DN<6>
J 0
(-5240 2235);
DISPLAY 0.659574 (-5240 2235);
PAINT MONO (-5240 2235);
DISPLAY INVISIBLE (-5240 2235);
FORCEPROP 1 LASTPIN (-5250 2225) BN 6
J 2
(-5238 2233);
DISPLAY 0.617021 (-5238 2233);
PAINT PINK (-5238 2233);
FORCEPROP 2 LAST CDS_LIB mstr_standard
J 0
(-5300 2225);
PAINT MONO (-5300 2225);
DISPLAY INVISIBLE (-5300 2225);
FORCEPROP 1 LAST BODY_TYPE PLUMBING
J 2
(-5300 2275);
DISPLAY 1.446809 (-5300 2275);
PAINT GREEN (-5300 2275);
DISPLAY INVISIBLE (-5300 2275);
FORCEPROP 1 LAST HDL_TAP TRUE
J 2
(-5625 2100);
DISPLAY 1.446809 (-5625 2100);
PAINT GREEN (-5625 2100);
DISPLAY INVISIBLE (-5625 2100);
FORCEPROP 1 LAST PATH I17
J 2
(-5298 2225);
DISPLAY 0.872340 (-5298 2225);
PAINT GREEN (-5298 2225);
DISPLAY INVISIBLE (-5298 2225);
FORCEADD TAP..1
R 2
(-5300 2275);
FORCEPROP 3 LASTPIN (-5250 2275) SIG_NAME UPI_CPU1_CPU0_P1P1_DN<5>
J 0
(-5240 2285);
DISPLAY 0.659574 (-5240 2285);
PAINT MONO (-5240 2285);
DISPLAY INVISIBLE (-5240 2285);
FORCEPROP 1 LASTPIN (-5250 2275) BN 5
J 2
(-5238 2283);
DISPLAY 0.617021 (-5238 2283);
PAINT PINK (-5238 2283);
FORCEPROP 2 LAST CDS_LIB mstr_standard
J 0
(-5300 2275);
PAINT MONO (-5300 2275);
DISPLAY INVISIBLE (-5300 2275);
FORCEPROP 1 LAST BODY_TYPE PLUMBING
J 2
(-5300 2325);
DISPLAY 1.446809 (-5300 2325);
PAINT GREEN (-5300 2325);
DISPLAY INVISIBLE (-5300 2325);
FORCEPROP 1 LAST HDL_TAP TRUE
J 2
(-5625 2150);
DISPLAY 1.446809 (-5625 2150);
PAINT GREEN (-5625 2150);
DISPLAY INVISIBLE (-5625 2150);
FORCEPROP 1 LAST PATH I18
J 2
(-5298 2275);
DISPLAY 0.872340 (-5298 2275);
PAINT GREEN (-5298 2275);
DISPLAY INVISIBLE (-5298 2275);
FORCEADD TAP..1
R 2
(-5300 2325);
FORCEPROP 3 LASTPIN (-5250 2325) SIG_NAME UPI_CPU1_CPU0_P1P1_DN<4>
J 0
(-5240 2335);
DISPLAY 0.659574 (-5240 2335);
PAINT MONO (-5240 2335);
DISPLAY INVISIBLE (-5240 2335);
FORCEPROP 1 LASTPIN (-5250 2325) BN 4
J 2
(-5238 2333);
DISPLAY 0.617021 (-5238 2333);
PAINT PINK (-5238 2333);
FORCEPROP 2 LAST CDS_LIB mstr_standard
J 0
(-5300 2325);
PAINT MONO (-5300 2325);
DISPLAY INVISIBLE (-5300 2325);
FORCEPROP 1 LAST BODY_TYPE PLUMBING
J 2
(-5300 2375);
DISPLAY 1.446809 (-5300 2375);
PAINT GREEN (-5300 2375);
DISPLAY INVISIBLE (-5300 2375);
FORCEPROP 1 LAST HDL_TAP TRUE
J 2
(-5625 2200);
DISPLAY 1.446809 (-5625 2200);
PAINT GREEN (-5625 2200);
DISPLAY INVISIBLE (-5625 2200);
FORCEPROP 1 LAST PATH I19
J 2
(-5298 2325);
DISPLAY 0.872340 (-5298 2325);
PAINT GREEN (-5298 2325);
DISPLAY INVISIBLE (-5298 2325);
FORCEADD OFFPAGE..1
(-6500 3625);
FORCEPROP 2 LAST $XR0 68 
J 0
(-6751 3625);
DISPLAY 0.638298 (-6751 3625);
PAINT MONO (-6751 3625);
FORCEPROP 2 LAST CDS_LIB mstr_standard
J 0
(-6500 3625);
PAINT MONO (-6500 3625);
DISPLAY INVISIBLE (-6500 3625);
FORCEPROP 1 LAST OFFPAGE TRUE
J 0
(-6175 3500);
DISPLAY 1.170213 (-6175 3500);
PAINT GREEN (-6175 3500);
DISPLAY INVISIBLE (-6175 3500);
FORCEPROP 1 LAST COMMENT_BODY TRUE
J 0
(-6375 3525);
DISPLAY 1.170213 (-6375 3525);
PAINT GREEN (-6375 3525);
DISPLAY INVISIBLE (-6375 3525);
FORCEPROP 2 LAST PATH I2
J 0
(-6450 3700);
DISPLAY 1.021277 (-6450 3700);
PAINT ORANGE (-6450 3700);
DISPLAY INVISIBLE (-6450 3700);
FORCEADD TAP..1
R 2
(-5300 2375);
FORCEPROP 3 LASTPIN (-5250 2375) SIG_NAME UPI_CPU1_CPU0_P1P1_DN<3>
J 0
(-5240 2385);
DISPLAY 0.659574 (-5240 2385);
PAINT MONO (-5240 2385);
DISPLAY INVISIBLE (-5240 2385);
FORCEPROP 1 LASTPIN (-5250 2375) BN 3
J 2
(-5238 2383);
DISPLAY 0.617021 (-5238 2383);
PAINT PINK (-5238 2383);
FORCEPROP 2 LAST CDS_LIB mstr_standard
J 0
(-5300 2375);
PAINT MONO (-5300 2375);
DISPLAY INVISIBLE (-5300 2375);
FORCEPROP 1 LAST BODY_TYPE PLUMBING
J 2
(-5300 2425);
DISPLAY 1.446809 (-5300 2425);
PAINT GREEN (-5300 2425);
DISPLAY INVISIBLE (-5300 2425);
FORCEPROP 1 LAST HDL_TAP TRUE
J 2
(-5625 2250);
DISPLAY 1.446809 (-5625 2250);
PAINT GREEN (-5625 2250);
DISPLAY INVISIBLE (-5625 2250);
FORCEPROP 1 LAST PATH I20
J 2
(-5298 2375);
DISPLAY 0.872340 (-5298 2375);
PAINT GREEN (-5298 2375);
DISPLAY INVISIBLE (-5298 2375);
FORCEADD TAP..1
R 2
(-5300 2425);
FORCEPROP 3 LASTPIN (-5250 2425) SIG_NAME UPI_CPU1_CPU0_P1P1_DN<2>
J 0
(-5240 2435);
DISPLAY 0.659574 (-5240 2435);
PAINT MONO (-5240 2435);
DISPLAY INVISIBLE (-5240 2435);
FORCEPROP 1 LASTPIN (-5250 2425) BN 2
J 2
(-5238 2433);
DISPLAY 0.617021 (-5238 2433);
PAINT PINK (-5238 2433);
FORCEPROP 2 LAST CDS_LIB mstr_standard
J 0
(-5300 2425);
PAINT MONO (-5300 2425);
DISPLAY INVISIBLE (-5300 2425);
FORCEPROP 1 LAST BODY_TYPE PLUMBING
J 2
(-5300 2475);
DISPLAY 1.446809 (-5300 2475);
PAINT GREEN (-5300 2475);
DISPLAY INVISIBLE (-5300 2475);
FORCEPROP 1 LAST HDL_TAP TRUE
J 2
(-5625 2300);
DISPLAY 1.446809 (-5625 2300);
PAINT GREEN (-5625 2300);
DISPLAY INVISIBLE (-5625 2300);
FORCEPROP 1 LAST PATH I21
J 2
(-5298 2425);
DISPLAY 0.872340 (-5298 2425);
PAINT GREEN (-5298 2425);
DISPLAY INVISIBLE (-5298 2425);
FORCEADD TAP..1
R 2
(-5300 2475);
FORCEPROP 3 LASTPIN (-5250 2475) SIG_NAME UPI_CPU1_CPU0_P1P1_DN<1>
J 0
(-5240 2485);
DISPLAY 0.659574 (-5240 2485);
PAINT MONO (-5240 2485);
DISPLAY INVISIBLE (-5240 2485);
FORCEPROP 1 LASTPIN (-5250 2475) BN 1
J 2
(-5238 2483);
DISPLAY 0.617021 (-5238 2483);
PAINT PINK (-5238 2483);
FORCEPROP 2 LAST CDS_LIB mstr_standard
J 0
(-5300 2475);
PAINT MONO (-5300 2475);
DISPLAY INVISIBLE (-5300 2475);
FORCEPROP 1 LAST BODY_TYPE PLUMBING
J 2
(-5300 2525);
DISPLAY 1.446809 (-5300 2525);
PAINT GREEN (-5300 2525);
DISPLAY INVISIBLE (-5300 2525);
FORCEPROP 1 LAST HDL_TAP TRUE
J 2
(-5625 2350);
DISPLAY 1.446809 (-5625 2350);
PAINT GREEN (-5625 2350);
DISPLAY INVISIBLE (-5625 2350);
FORCEPROP 1 LAST PATH I22
J 2
(-5298 2475);
DISPLAY 0.872340 (-5298 2475);
PAINT GREEN (-5298 2475);
DISPLAY INVISIBLE (-5298 2475);
FORCEADD TAP..1
R 2
(-5300 2525);
FORCEPROP 3 LASTPIN (-5250 2525) SIG_NAME UPI_CPU1_CPU0_P1P1_DN<0>
J 0
(-5240 2535);
DISPLAY 0.659574 (-5240 2535);
PAINT MONO (-5240 2535);
DISPLAY INVISIBLE (-5240 2535);
FORCEPROP 1 LASTPIN (-5250 2525) BN 0
J 2
(-5238 2533);
DISPLAY 0.617021 (-5238 2533);
PAINT PINK (-5238 2533);
FORCEPROP 2 LAST CDS_LIB mstr_standard
J 0
(-5300 2525);
PAINT MONO (-5300 2525);
DISPLAY INVISIBLE (-5300 2525);
FORCEPROP 1 LAST BODY_TYPE PLUMBING
J 2
(-5300 2575);
DISPLAY 1.446809 (-5300 2575);
PAINT GREEN (-5300 2575);
DISPLAY INVISIBLE (-5300 2575);
FORCEPROP 1 LAST HDL_TAP TRUE
J 2
(-5625 2400);
DISPLAY 1.446809 (-5625 2400);
PAINT GREEN (-5625 2400);
DISPLAY INVISIBLE (-5625 2400);
FORCEPROP 1 LAST PATH I23
J 2
(-5298 2525);
DISPLAY 0.872340 (-5298 2525);
PAINT GREEN (-5298 2525);
DISPLAY INVISIBLE (-5298 2525);
FORCEADD TAP..1
R 2
(-5300 2625);
FORCEPROP 3 LASTPIN (-5250 2625) SIG_NAME UPI_CPU1_CPU0_P1P1_DP<19>
J 0
(-5240 2635);
DISPLAY 0.659574 (-5240 2635);
PAINT MONO (-5240 2635);
DISPLAY INVISIBLE (-5240 2635);
FORCEPROP 1 LASTPIN (-5250 2625) BN 19
J 2
(-5238 2633);
DISPLAY 0.617021 (-5238 2633);
PAINT PINK (-5238 2633);
FORCEPROP 2 LAST CDS_LIB mstr_standard
J 0
(-5300 2625);
PAINT MONO (-5300 2625);
DISPLAY INVISIBLE (-5300 2625);
FORCEPROP 1 LAST BODY_TYPE PLUMBING
J 2
(-5300 2675);
DISPLAY 1.446809 (-5300 2675);
PAINT GREEN (-5300 2675);
DISPLAY INVISIBLE (-5300 2675);
FORCEPROP 1 LAST HDL_TAP TRUE
J 2
(-5625 2500);
DISPLAY 1.446809 (-5625 2500);
PAINT GREEN (-5625 2500);
DISPLAY INVISIBLE (-5625 2500);
FORCEPROP 1 LAST PATH I24
J 2
(-5298 2625);
DISPLAY 0.872340 (-5298 2625);
PAINT GREEN (-5298 2625);
DISPLAY INVISIBLE (-5298 2625);
FORCEADD TAP..1
R 2
(-5300 2775);
FORCEPROP 3 LASTPIN (-5250 2775) SIG_NAME UPI_CPU1_CPU0_P1P1_DP<16>
J 0
(-5240 2785);
DISPLAY 0.659574 (-5240 2785);
PAINT MONO (-5240 2785);
DISPLAY INVISIBLE (-5240 2785);
FORCEPROP 1 LASTPIN (-5250 2775) BN 16
J 2
(-5238 2783);
DISPLAY 0.617021 (-5238 2783);
PAINT PINK (-5238 2783);
FORCEPROP 2 LAST CDS_LIB mstr_standard
J 0
(-5300 2775);
PAINT MONO (-5300 2775);
DISPLAY INVISIBLE (-5300 2775);
FORCEPROP 1 LAST BODY_TYPE PLUMBING
J 2
(-5300 2825);
DISPLAY 1.446809 (-5300 2825);
PAINT GREEN (-5300 2825);
DISPLAY INVISIBLE (-5300 2825);
FORCEPROP 1 LAST HDL_TAP TRUE
J 2
(-5625 2650);
DISPLAY 1.446809 (-5625 2650);
PAINT GREEN (-5625 2650);
DISPLAY INVISIBLE (-5625 2650);
FORCEPROP 1 LAST PATH I25
J 2
(-5298 2775);
DISPLAY 0.872340 (-5298 2775);
PAINT GREEN (-5298 2775);
DISPLAY INVISIBLE (-5298 2775);
FORCEADD TAP..1
R 2
(-5300 2725);
FORCEPROP 3 LASTPIN (-5250 2725) SIG_NAME UPI_CPU1_CPU0_P1P1_DP<17>
J 0
(-5240 2735);
DISPLAY 0.659574 (-5240 2735);
PAINT MONO (-5240 2735);
DISPLAY INVISIBLE (-5240 2735);
FORCEPROP 1 LASTPIN (-5250 2725) BN 17
J 2
(-5238 2733);
DISPLAY 0.617021 (-5238 2733);
PAINT PINK (-5238 2733);
FORCEPROP 2 LAST CDS_LIB mstr_standard
J 0
(-5300 2725);
PAINT MONO (-5300 2725);
DISPLAY INVISIBLE (-5300 2725);
FORCEPROP 1 LAST BODY_TYPE PLUMBING
J 2
(-5300 2775);
DISPLAY 1.446809 (-5300 2775);
PAINT GREEN (-5300 2775);
DISPLAY INVISIBLE (-5300 2775);
FORCEPROP 1 LAST HDL_TAP TRUE
J 2
(-5625 2600);
DISPLAY 1.446809 (-5625 2600);
PAINT GREEN (-5625 2600);
DISPLAY INVISIBLE (-5625 2600);
FORCEPROP 1 LAST PATH I26
J 2
(-5298 2725);
DISPLAY 0.872340 (-5298 2725);
PAINT GREEN (-5298 2725);
DISPLAY INVISIBLE (-5298 2725);
FORCEADD TAP..1
R 2
(-5300 2675);
FORCEPROP 3 LASTPIN (-5250 2675) SIG_NAME UPI_CPU1_CPU0_P1P1_DP<18>
J 0
(-5240 2685);
DISPLAY 0.659574 (-5240 2685);
PAINT MONO (-5240 2685);
DISPLAY INVISIBLE (-5240 2685);
FORCEPROP 1 LASTPIN (-5250 2675) BN 18
J 2
(-5238 2683);
DISPLAY 0.617021 (-5238 2683);
PAINT PINK (-5238 2683);
FORCEPROP 2 LAST CDS_LIB mstr_standard
J 0
(-5300 2675);
PAINT MONO (-5300 2675);
DISPLAY INVISIBLE (-5300 2675);
FORCEPROP 1 LAST BODY_TYPE PLUMBING
J 2
(-5300 2725);
DISPLAY 1.446809 (-5300 2725);
PAINT GREEN (-5300 2725);
DISPLAY INVISIBLE (-5300 2725);
FORCEPROP 1 LAST HDL_TAP TRUE
J 2
(-5625 2550);
DISPLAY 1.446809 (-5625 2550);
PAINT GREEN (-5625 2550);
DISPLAY INVISIBLE (-5625 2550);
FORCEPROP 1 LAST PATH I27
J 2
(-5298 2675);
DISPLAY 0.872340 (-5298 2675);
PAINT GREEN (-5298 2675);
DISPLAY INVISIBLE (-5298 2675);
FORCEADD TAP..1
R 2
(-5300 2825);
FORCEPROP 3 LASTPIN (-5250 2825) SIG_NAME UPI_CPU1_CPU0_P1P1_DP<15>
J 0
(-5240 2835);
DISPLAY 0.659574 (-5240 2835);
PAINT MONO (-5240 2835);
DISPLAY INVISIBLE (-5240 2835);
FORCEPROP 1 LASTPIN (-5250 2825) BN 15
J 2
(-5238 2833);
DISPLAY 0.617021 (-5238 2833);
PAINT PINK (-5238 2833);
FORCEPROP 2 LAST CDS_LIB mstr_standard
J 0
(-5300 2825);
PAINT MONO (-5300 2825);
DISPLAY INVISIBLE (-5300 2825);
FORCEPROP 1 LAST BODY_TYPE PLUMBING
J 2
(-5300 2875);
DISPLAY 1.446809 (-5300 2875);
PAINT GREEN (-5300 2875);
DISPLAY INVISIBLE (-5300 2875);
FORCEPROP 1 LAST HDL_TAP TRUE
J 2
(-5625 2700);
DISPLAY 1.446809 (-5625 2700);
PAINT GREEN (-5625 2700);
DISPLAY INVISIBLE (-5625 2700);
FORCEPROP 1 LAST PATH I28
J 2
(-5298 2825);
DISPLAY 0.872340 (-5298 2825);
PAINT GREEN (-5298 2825);
DISPLAY INVISIBLE (-5298 2825);
FORCEADD TAP..1
R 2
(-5300 2875);
FORCEPROP 3 LASTPIN (-5250 2875) SIG_NAME UPI_CPU1_CPU0_P1P1_DP<14>
J 0
(-5240 2885);
DISPLAY 0.659574 (-5240 2885);
PAINT MONO (-5240 2885);
DISPLAY INVISIBLE (-5240 2885);
FORCEPROP 1 LASTPIN (-5250 2875) BN 14
J 2
(-5238 2883);
DISPLAY 0.617021 (-5238 2883);
PAINT PINK (-5238 2883);
FORCEPROP 2 LAST CDS_LIB mstr_standard
J 0
(-5300 2875);
PAINT MONO (-5300 2875);
DISPLAY INVISIBLE (-5300 2875);
FORCEPROP 1 LAST BODY_TYPE PLUMBING
J 2
(-5300 2925);
DISPLAY 1.446809 (-5300 2925);
PAINT GREEN (-5300 2925);
DISPLAY INVISIBLE (-5300 2925);
FORCEPROP 1 LAST HDL_TAP TRUE
J 2
(-5625 2750);
DISPLAY 1.446809 (-5625 2750);
PAINT GREEN (-5625 2750);
DISPLAY INVISIBLE (-5625 2750);
FORCEPROP 1 LAST PATH I29
J 2
(-5298 2875);
DISPLAY 0.872340 (-5298 2875);
PAINT GREEN (-5298 2875);
DISPLAY INVISIBLE (-5298 2875);
FORCEADD TAP..1
R 2
(-5300 1625);
FORCEPROP 3 LASTPIN (-5250 1625) SIG_NAME UPI_CPU1_CPU0_P1P1_DN<18>
J 0
(-5240 1635);
DISPLAY 0.659574 (-5240 1635);
PAINT MONO (-5240 1635);
DISPLAY INVISIBLE (-5240 1635);
FORCEPROP 1 LASTPIN (-5250 1625) BN 18
J 2
(-5238 1633);
DISPLAY 0.617021 (-5238 1633);
PAINT PINK (-5238 1633);
FORCEPROP 2 LAST CDS_LIB mstr_standard
J 0
(-5300 1625);
PAINT MONO (-5300 1625);
DISPLAY INVISIBLE (-5300 1625);
FORCEPROP 1 LAST BODY_TYPE PLUMBING
J 2
(-5300 1675);
DISPLAY 1.446809 (-5300 1675);
PAINT GREEN (-5300 1675);
DISPLAY INVISIBLE (-5300 1675);
FORCEPROP 1 LAST HDL_TAP TRUE
J 2
(-5625 1500);
DISPLAY 1.446809 (-5625 1500);
PAINT GREEN (-5625 1500);
DISPLAY INVISIBLE (-5625 1500);
FORCEPROP 1 LAST PATH I3
J 2
(-5298 1625);
DISPLAY 0.872340 (-5298 1625);
PAINT GREEN (-5298 1625);
DISPLAY INVISIBLE (-5298 1625);
FORCEADD TAP..1
R 2
(-5300 2925);
FORCEPROP 3 LASTPIN (-5250 2925) SIG_NAME UPI_CPU1_CPU0_P1P1_DP<13>
J 0
(-5240 2935);
DISPLAY 0.659574 (-5240 2935);
PAINT MONO (-5240 2935);
DISPLAY INVISIBLE (-5240 2935);
FORCEPROP 1 LASTPIN (-5250 2925) BN 13
J 2
(-5238 2933);
DISPLAY 0.617021 (-5238 2933);
PAINT PINK (-5238 2933);
FORCEPROP 2 LAST CDS_LIB mstr_standard
J 0
(-5300 2925);
PAINT MONO (-5300 2925);
DISPLAY INVISIBLE (-5300 2925);
FORCEPROP 1 LAST BODY_TYPE PLUMBING
J 2
(-5300 2975);
DISPLAY 1.446809 (-5300 2975);
PAINT GREEN (-5300 2975);
DISPLAY INVISIBLE (-5300 2975);
FORCEPROP 1 LAST HDL_TAP TRUE
J 2
(-5625 2800);
DISPLAY 1.446809 (-5625 2800);
PAINT GREEN (-5625 2800);
DISPLAY INVISIBLE (-5625 2800);
FORCEPROP 1 LAST PATH I30
J 2
(-5298 2925);
DISPLAY 0.872340 (-5298 2925);
PAINT GREEN (-5298 2925);
DISPLAY INVISIBLE (-5298 2925);
FORCEADD TAP..1
R 2
(-5300 2975);
FORCEPROP 3 LASTPIN (-5250 2975) SIG_NAME UPI_CPU1_CPU0_P1P1_DP<12>
J 0
(-5240 2985);
DISPLAY 0.659574 (-5240 2985);
PAINT MONO (-5240 2985);
DISPLAY INVISIBLE (-5240 2985);
FORCEPROP 1 LASTPIN (-5250 2975) BN 12
J 2
(-5238 2983);
DISPLAY 0.617021 (-5238 2983);
PAINT PINK (-5238 2983);
FORCEPROP 2 LAST CDS_LIB mstr_standard
J 0
(-5300 2975);
PAINT MONO (-5300 2975);
DISPLAY INVISIBLE (-5300 2975);
FORCEPROP 1 LAST BODY_TYPE PLUMBING
J 2
(-5300 3025);
DISPLAY 1.446809 (-5300 3025);
PAINT GREEN (-5300 3025);
DISPLAY INVISIBLE (-5300 3025);
FORCEPROP 1 LAST HDL_TAP TRUE
J 2
(-5625 2850);
DISPLAY 1.446809 (-5625 2850);
PAINT GREEN (-5625 2850);
DISPLAY INVISIBLE (-5625 2850);
FORCEPROP 1 LAST PATH I31
J 2
(-5298 2975);
DISPLAY 0.872340 (-5298 2975);
PAINT GREEN (-5298 2975);
DISPLAY INVISIBLE (-5298 2975);
FORCEADD TAP..1
R 2
(-5300 3075);
FORCEPROP 3 LASTPIN (-5250 3075) SIG_NAME UPI_CPU1_CPU0_P1P1_DP<10>
J 0
(-5240 3085);
DISPLAY 0.659574 (-5240 3085);
PAINT MONO (-5240 3085);
DISPLAY INVISIBLE (-5240 3085);
FORCEPROP 1 LASTPIN (-5250 3075) BN 10
J 2
(-5238 3083);
DISPLAY 0.617021 (-5238 3083);
PAINT PINK (-5238 3083);
FORCEPROP 2 LAST CDS_LIB mstr_standard
J 0
(-5300 3075);
PAINT MONO (-5300 3075);
DISPLAY INVISIBLE (-5300 3075);
FORCEPROP 1 LAST BODY_TYPE PLUMBING
J 2
(-5300 3125);
DISPLAY 1.446809 (-5300 3125);
PAINT GREEN (-5300 3125);
DISPLAY INVISIBLE (-5300 3125);
FORCEPROP 1 LAST HDL_TAP TRUE
J 2
(-5625 2950);
DISPLAY 1.446809 (-5625 2950);
PAINT GREEN (-5625 2950);
DISPLAY INVISIBLE (-5625 2950);
FORCEPROP 1 LAST PATH I32
J 2
(-5298 3075);
DISPLAY 0.872340 (-5298 3075);
PAINT GREEN (-5298 3075);
DISPLAY INVISIBLE (-5298 3075);
FORCEADD TAP..1
R 2
(-5300 3025);
FORCEPROP 3 LASTPIN (-5250 3025) SIG_NAME UPI_CPU1_CPU0_P1P1_DP<11>
J 0
(-5240 3035);
DISPLAY 0.659574 (-5240 3035);
PAINT MONO (-5240 3035);
DISPLAY INVISIBLE (-5240 3035);
FORCEPROP 1 LASTPIN (-5250 3025) BN 11
J 2
(-5238 3033);
DISPLAY 0.617021 (-5238 3033);
PAINT PINK (-5238 3033);
FORCEPROP 2 LAST CDS_LIB mstr_standard
J 0
(-5300 3025);
PAINT MONO (-5300 3025);
DISPLAY INVISIBLE (-5300 3025);
FORCEPROP 1 LAST BODY_TYPE PLUMBING
J 2
(-5300 3075);
DISPLAY 1.446809 (-5300 3075);
PAINT GREEN (-5300 3075);
DISPLAY INVISIBLE (-5300 3075);
FORCEPROP 1 LAST HDL_TAP TRUE
J 2
(-5625 2900);
DISPLAY 1.446809 (-5625 2900);
PAINT GREEN (-5625 2900);
DISPLAY INVISIBLE (-5625 2900);
FORCEPROP 1 LAST PATH I33
J 2
(-5298 3025);
DISPLAY 0.872340 (-5298 3025);
PAINT GREEN (-5298 3025);
DISPLAY INVISIBLE (-5298 3025);
FORCEADD TAP..1
R 2
(-5300 3125);
FORCEPROP 3 LASTPIN (-5250 3125) SIG_NAME UPI_CPU1_CPU0_P1P1_DP<9>
J 0
(-5240 3135);
DISPLAY 0.659574 (-5240 3135);
PAINT MONO (-5240 3135);
DISPLAY INVISIBLE (-5240 3135);
FORCEPROP 1 LASTPIN (-5250 3125) BN 9
J 2
(-5238 3133);
DISPLAY 0.617021 (-5238 3133);
PAINT PINK (-5238 3133);
FORCEPROP 2 LAST CDS_LIB mstr_standard
J 0
(-5300 3125);
PAINT MONO (-5300 3125);
DISPLAY INVISIBLE (-5300 3125);
FORCEPROP 1 LAST BODY_TYPE PLUMBING
J 2
(-5300 3175);
DISPLAY 1.446809 (-5300 3175);
PAINT GREEN (-5300 3175);
DISPLAY INVISIBLE (-5300 3175);
FORCEPROP 1 LAST HDL_TAP TRUE
J 2
(-5625 3000);
DISPLAY 1.446809 (-5625 3000);
PAINT GREEN (-5625 3000);
DISPLAY INVISIBLE (-5625 3000);
FORCEPROP 1 LAST PATH I34
J 2
(-5298 3125);
DISPLAY 0.872340 (-5298 3125);
PAINT GREEN (-5298 3125);
DISPLAY INVISIBLE (-5298 3125);
FORCEADD TAP..1
R 2
(-5300 3175);
FORCEPROP 3 LASTPIN (-5250 3175) SIG_NAME UPI_CPU1_CPU0_P1P1_DP<8>
J 0
(-5240 3185);
DISPLAY 0.659574 (-5240 3185);
PAINT MONO (-5240 3185);
DISPLAY INVISIBLE (-5240 3185);
FORCEPROP 1 LASTPIN (-5250 3175) BN 8
J 2
(-5238 3183);
DISPLAY 0.617021 (-5238 3183);
PAINT PINK (-5238 3183);
FORCEPROP 2 LAST CDS_LIB mstr_standard
J 0
(-5300 3175);
PAINT MONO (-5300 3175);
DISPLAY INVISIBLE (-5300 3175);
FORCEPROP 1 LAST BODY_TYPE PLUMBING
J 2
(-5300 3225);
DISPLAY 1.446809 (-5300 3225);
PAINT GREEN (-5300 3225);
DISPLAY INVISIBLE (-5300 3225);
FORCEPROP 1 LAST HDL_TAP TRUE
J 2
(-5625 3050);
DISPLAY 1.446809 (-5625 3050);
PAINT GREEN (-5625 3050);
DISPLAY INVISIBLE (-5625 3050);
FORCEPROP 1 LAST PATH I35
J 2
(-5298 3175);
DISPLAY 0.872340 (-5298 3175);
PAINT GREEN (-5298 3175);
DISPLAY INVISIBLE (-5298 3175);
FORCEADD TAP..1
R 2
(-5300 3225);
FORCEPROP 3 LASTPIN (-5250 3225) SIG_NAME UPI_CPU1_CPU0_P1P1_DP<7>
J 0
(-5240 3235);
DISPLAY 0.659574 (-5240 3235);
PAINT MONO (-5240 3235);
DISPLAY INVISIBLE (-5240 3235);
FORCEPROP 1 LASTPIN (-5250 3225) BN 7
J 2
(-5238 3233);
DISPLAY 0.617021 (-5238 3233);
PAINT PINK (-5238 3233);
FORCEPROP 2 LAST CDS_LIB mstr_standard
J 0
(-5300 3225);
PAINT MONO (-5300 3225);
DISPLAY INVISIBLE (-5300 3225);
FORCEPROP 1 LAST BODY_TYPE PLUMBING
J 2
(-5300 3275);
DISPLAY 1.446809 (-5300 3275);
PAINT GREEN (-5300 3275);
DISPLAY INVISIBLE (-5300 3275);
FORCEPROP 1 LAST HDL_TAP TRUE
J 2
(-5625 3100);
DISPLAY 1.446809 (-5625 3100);
PAINT GREEN (-5625 3100);
DISPLAY INVISIBLE (-5625 3100);
FORCEPROP 1 LAST PATH I36
J 2
(-5298 3225);
DISPLAY 0.872340 (-5298 3225);
PAINT GREEN (-5298 3225);
DISPLAY INVISIBLE (-5298 3225);
FORCEADD TAP..1
R 2
(-5300 3325);
FORCEPROP 3 LASTPIN (-5250 3325) SIG_NAME UPI_CPU1_CPU0_P1P1_DP<5>
J 0
(-5240 3335);
DISPLAY 0.659574 (-5240 3335);
PAINT MONO (-5240 3335);
DISPLAY INVISIBLE (-5240 3335);
FORCEPROP 1 LASTPIN (-5250 3325) BN 5
J 2
(-5238 3333);
DISPLAY 0.617021 (-5238 3333);
PAINT PINK (-5238 3333);
FORCEPROP 2 LAST CDS_LIB mstr_standard
J 0
(-5300 3325);
PAINT MONO (-5300 3325);
DISPLAY INVISIBLE (-5300 3325);
FORCEPROP 1 LAST BODY_TYPE PLUMBING
J 2
(-5300 3375);
DISPLAY 1.446809 (-5300 3375);
PAINT GREEN (-5300 3375);
DISPLAY INVISIBLE (-5300 3375);
FORCEPROP 1 LAST HDL_TAP TRUE
J 2
(-5625 3200);
DISPLAY 1.446809 (-5625 3200);
PAINT GREEN (-5625 3200);
DISPLAY INVISIBLE (-5625 3200);
FORCEPROP 1 LAST PATH I37
J 2
(-5298 3325);
DISPLAY 0.872340 (-5298 3325);
PAINT GREEN (-5298 3325);
DISPLAY INVISIBLE (-5298 3325);
FORCEADD TAP..1
R 2
(-5300 3275);
FORCEPROP 3 LASTPIN (-5250 3275) SIG_NAME UPI_CPU1_CPU0_P1P1_DP<6>
J 0
(-5240 3285);
DISPLAY 0.659574 (-5240 3285);
PAINT MONO (-5240 3285);
DISPLAY INVISIBLE (-5240 3285);
FORCEPROP 1 LASTPIN (-5250 3275) BN 6
J 2
(-5238 3283);
DISPLAY 0.617021 (-5238 3283);
PAINT PINK (-5238 3283);
FORCEPROP 2 LAST CDS_LIB mstr_standard
J 0
(-5300 3275);
PAINT MONO (-5300 3275);
DISPLAY INVISIBLE (-5300 3275);
FORCEPROP 1 LAST BODY_TYPE PLUMBING
J 2
(-5300 3325);
DISPLAY 1.446809 (-5300 3325);
PAINT GREEN (-5300 3325);
DISPLAY INVISIBLE (-5300 3325);
FORCEPROP 1 LAST HDL_TAP TRUE
J 2
(-5625 3150);
DISPLAY 1.446809 (-5625 3150);
PAINT GREEN (-5625 3150);
DISPLAY INVISIBLE (-5625 3150);
FORCEPROP 1 LAST PATH I38
J 2
(-5298 3275);
DISPLAY 0.872340 (-5298 3275);
PAINT GREEN (-5298 3275);
DISPLAY INVISIBLE (-5298 3275);
FORCEADD TAP..1
R 2
(-5300 3375);
FORCEPROP 3 LASTPIN (-5250 3375) SIG_NAME UPI_CPU1_CPU0_P1P1_DP<4>
J 0
(-5240 3385);
DISPLAY 0.659574 (-5240 3385);
PAINT MONO (-5240 3385);
DISPLAY INVISIBLE (-5240 3385);
FORCEPROP 1 LASTPIN (-5250 3375) BN 4
J 2
(-5238 3383);
DISPLAY 0.617021 (-5238 3383);
PAINT PINK (-5238 3383);
FORCEPROP 2 LAST CDS_LIB mstr_standard
J 0
(-5300 3375);
PAINT MONO (-5300 3375);
DISPLAY INVISIBLE (-5300 3375);
FORCEPROP 1 LAST BODY_TYPE PLUMBING
J 2
(-5300 3425);
DISPLAY 1.446809 (-5300 3425);
PAINT GREEN (-5300 3425);
DISPLAY INVISIBLE (-5300 3425);
FORCEPROP 1 LAST HDL_TAP TRUE
J 2
(-5625 3250);
DISPLAY 1.446809 (-5625 3250);
PAINT GREEN (-5625 3250);
DISPLAY INVISIBLE (-5625 3250);
FORCEPROP 1 LAST PATH I39
J 2
(-5298 3375);
DISPLAY 0.872340 (-5298 3375);
PAINT GREEN (-5298 3375);
DISPLAY INVISIBLE (-5298 3375);
FORCEADD TAP..1
R 2
(-5300 1575);
FORCEPROP 3 LASTPIN (-5250 1575) SIG_NAME UPI_CPU1_CPU0_P1P1_DN<19>
J 0
(-5240 1585);
DISPLAY 0.659574 (-5240 1585);
PAINT MONO (-5240 1585);
DISPLAY INVISIBLE (-5240 1585);
FORCEPROP 1 LASTPIN (-5250 1575) BN 19
J 2
(-5238 1583);
DISPLAY 0.617021 (-5238 1583);
PAINT PINK (-5238 1583);
FORCEPROP 2 LAST CDS_LIB mstr_standard
J 0
(-5300 1575);
PAINT MONO (-5300 1575);
DISPLAY INVISIBLE (-5300 1575);
FORCEPROP 1 LAST BODY_TYPE PLUMBING
J 2
(-5300 1625);
DISPLAY 1.446809 (-5300 1625);
PAINT GREEN (-5300 1625);
DISPLAY INVISIBLE (-5300 1625);
FORCEPROP 1 LAST HDL_TAP TRUE
J 2
(-5625 1450);
DISPLAY 1.446809 (-5625 1450);
PAINT GREEN (-5625 1450);
DISPLAY INVISIBLE (-5625 1450);
FORCEPROP 1 LAST PATH I4
J 2
(-5298 1575);
DISPLAY 0.872340 (-5298 1575);
PAINT GREEN (-5298 1575);
DISPLAY INVISIBLE (-5298 1575);
FORCEADD TAP..1
R 2
(-5300 3425);
FORCEPROP 3 LASTPIN (-5250 3425) SIG_NAME UPI_CPU1_CPU0_P1P1_DP<3>
J 0
(-5240 3435);
DISPLAY 0.659574 (-5240 3435);
PAINT MONO (-5240 3435);
DISPLAY INVISIBLE (-5240 3435);
FORCEPROP 1 LASTPIN (-5250 3425) BN 3
J 2
(-5238 3433);
DISPLAY 0.617021 (-5238 3433);
PAINT PINK (-5238 3433);
FORCEPROP 2 LAST CDS_LIB mstr_standard
J 0
(-5300 3425);
PAINT MONO (-5300 3425);
DISPLAY INVISIBLE (-5300 3425);
FORCEPROP 1 LAST BODY_TYPE PLUMBING
J 2
(-5300 3475);
DISPLAY 1.446809 (-5300 3475);
PAINT GREEN (-5300 3475);
DISPLAY INVISIBLE (-5300 3475);
FORCEPROP 1 LAST HDL_TAP TRUE
J 2
(-5625 3300);
DISPLAY 1.446809 (-5625 3300);
PAINT GREEN (-5625 3300);
DISPLAY INVISIBLE (-5625 3300);
FORCEPROP 1 LAST PATH I40
J 2
(-5298 3425);
DISPLAY 0.872340 (-5298 3425);
PAINT GREEN (-5298 3425);
DISPLAY INVISIBLE (-5298 3425);
FORCEADD TAP..1
R 2
(-5300 3475);
FORCEPROP 3 LASTPIN (-5250 3475) SIG_NAME UPI_CPU1_CPU0_P1P1_DP<2>
J 0
(-5240 3485);
DISPLAY 0.659574 (-5240 3485);
PAINT MONO (-5240 3485);
DISPLAY INVISIBLE (-5240 3485);
FORCEPROP 1 LASTPIN (-5250 3475) BN 2
J 2
(-5238 3483);
DISPLAY 0.617021 (-5238 3483);
PAINT PINK (-5238 3483);
FORCEPROP 2 LAST CDS_LIB mstr_standard
J 0
(-5300 3475);
PAINT MONO (-5300 3475);
DISPLAY INVISIBLE (-5300 3475);
FORCEPROP 1 LAST BODY_TYPE PLUMBING
J 2
(-5300 3525);
DISPLAY 1.446809 (-5300 3525);
PAINT GREEN (-5300 3525);
DISPLAY INVISIBLE (-5300 3525);
FORCEPROP 1 LAST HDL_TAP TRUE
J 2
(-5625 3350);
DISPLAY 1.446809 (-5625 3350);
PAINT GREEN (-5625 3350);
DISPLAY INVISIBLE (-5625 3350);
FORCEPROP 1 LAST PATH I41
J 2
(-5298 3475);
DISPLAY 0.872340 (-5298 3475);
PAINT GREEN (-5298 3475);
DISPLAY INVISIBLE (-5298 3475);
FORCEADD TAP..1
R 2
(-5300 3575);
FORCEPROP 3 LASTPIN (-5250 3575) SIG_NAME UPI_CPU1_CPU0_P1P1_DP<0>
J 0
(-5240 3585);
DISPLAY 0.659574 (-5240 3585);
PAINT MONO (-5240 3585);
DISPLAY INVISIBLE (-5240 3585);
FORCEPROP 1 LASTPIN (-5250 3575) BN 0
J 2
(-5238 3583);
DISPLAY 0.617021 (-5238 3583);
PAINT PINK (-5238 3583);
FORCEPROP 2 LAST CDS_LIB mstr_standard
J 0
(-5300 3575);
PAINT MONO (-5300 3575);
DISPLAY INVISIBLE (-5300 3575);
FORCEPROP 1 LAST BODY_TYPE PLUMBING
J 2
(-5300 3625);
DISPLAY 1.446809 (-5300 3625);
PAINT GREEN (-5300 3625);
DISPLAY INVISIBLE (-5300 3625);
FORCEPROP 1 LAST HDL_TAP TRUE
J 2
(-5625 3450);
DISPLAY 1.446809 (-5625 3450);
PAINT GREEN (-5625 3450);
DISPLAY INVISIBLE (-5625 3450);
FORCEPROP 1 LAST PATH I42
J 2
(-5298 3575);
DISPLAY 0.872340 (-5298 3575);
PAINT GREEN (-5298 3575);
DISPLAY INVISIBLE (-5298 3575);
FORCEADD TAP..1
R 2
(-5300 3525);
FORCEPROP 3 LASTPIN (-5250 3525) SIG_NAME UPI_CPU1_CPU0_P1P1_DP<1>
J 0
(-5240 3535);
DISPLAY 0.659574 (-5240 3535);
PAINT MONO (-5240 3535);
DISPLAY INVISIBLE (-5240 3535);
FORCEPROP 1 LASTPIN (-5250 3525) BN 1
J 2
(-5238 3533);
DISPLAY 0.617021 (-5238 3533);
PAINT PINK (-5238 3533);
FORCEPROP 2 LAST CDS_LIB mstr_standard
J 0
(-5300 3525);
PAINT MONO (-5300 3525);
DISPLAY INVISIBLE (-5300 3525);
FORCEPROP 1 LAST BODY_TYPE PLUMBING
J 2
(-5300 3575);
DISPLAY 1.446809 (-5300 3575);
PAINT GREEN (-5300 3575);
DISPLAY INVISIBLE (-5300 3575);
FORCEPROP 1 LAST HDL_TAP TRUE
J 2
(-5625 3400);
DISPLAY 1.446809 (-5625 3400);
PAINT GREEN (-5625 3400);
DISPLAY INVISIBLE (-5625 3400);
FORCEPROP 1 LAST PATH I43
J 2
(-5298 3525);
DISPLAY 0.872340 (-5298 3525);
PAINT GREEN (-5298 3525);
DISPLAY INVISIBLE (-5298 3525);
FORCEADD TAP..1
(-2975 1575);
FORCEPROP 3 LASTPIN (-3025 1575) SIG_NAME UPI_CPU0_CPU1_P1P1_DN<19>
J 0
(-3015 1585);
DISPLAY 0.659574 (-3015 1585);
PAINT MONO (-3015 1585);
DISPLAY INVISIBLE (-3015 1585);
FORCEPROP 1 LASTPIN (-3025 1575) BN 19
J 0
(-3037 1583);
DISPLAY 0.617021 (-3037 1583);
PAINT PINK (-3037 1583);
FORCEPROP 2 LAST CDS_LIB mstr_standard
J 0
(-2975 1575);
PAINT MONO (-2975 1575);
DISPLAY INVISIBLE (-2975 1575);
FORCEPROP 1 LAST BODY_TYPE PLUMBING
J 0
(-2975 1625);
DISPLAY 1.446809 (-2975 1625);
PAINT GREEN (-2975 1625);
DISPLAY INVISIBLE (-2975 1625);
FORCEPROP 1 LAST HDL_TAP TRUE
J 0
(-2650 1450);
DISPLAY 1.446809 (-2650 1450);
PAINT GREEN (-2650 1450);
DISPLAY INVISIBLE (-2650 1450);
FORCEPROP 1 LAST PATH I44
J 0
(-2977 1575);
DISPLAY 0.872340 (-2977 1575);
PAINT GREEN (-2977 1575);
DISPLAY INVISIBLE (-2977 1575);
FORCEADD TAP..1
(-2975 1625);
FORCEPROP 3 LASTPIN (-3025 1625) SIG_NAME UPI_CPU0_CPU1_P1P1_DN<18>
J 0
(-3015 1635);
DISPLAY 0.659574 (-3015 1635);
PAINT MONO (-3015 1635);
DISPLAY INVISIBLE (-3015 1635);
FORCEPROP 1 LASTPIN (-3025 1625) BN 18
J 0
(-3037 1633);
DISPLAY 0.617021 (-3037 1633);
PAINT PINK (-3037 1633);
FORCEPROP 2 LAST CDS_LIB mstr_standard
J 0
(-2975 1625);
PAINT MONO (-2975 1625);
DISPLAY INVISIBLE (-2975 1625);
FORCEPROP 1 LAST BODY_TYPE PLUMBING
J 0
(-2975 1675);
DISPLAY 1.446809 (-2975 1675);
PAINT GREEN (-2975 1675);
DISPLAY INVISIBLE (-2975 1675);
FORCEPROP 1 LAST HDL_TAP TRUE
J 0
(-2650 1500);
DISPLAY 1.446809 (-2650 1500);
PAINT GREEN (-2650 1500);
DISPLAY INVISIBLE (-2650 1500);
FORCEPROP 1 LAST PATH I45
J 0
(-2977 1625);
DISPLAY 0.872340 (-2977 1625);
PAINT GREEN (-2977 1625);
DISPLAY INVISIBLE (-2977 1625);
FORCEADD TAP..1
(-2975 1675);
FORCEPROP 3 LASTPIN (-3025 1675) SIG_NAME UPI_CPU0_CPU1_P1P1_DN<17>
J 0
(-3015 1685);
DISPLAY 0.659574 (-3015 1685);
PAINT MONO (-3015 1685);
DISPLAY INVISIBLE (-3015 1685);
FORCEPROP 1 LASTPIN (-3025 1675) BN 17
J 0
(-3037 1683);
DISPLAY 0.617021 (-3037 1683);
PAINT PINK (-3037 1683);
FORCEPROP 2 LAST CDS_LIB mstr_standard
J 0
(-2975 1675);
PAINT MONO (-2975 1675);
DISPLAY INVISIBLE (-2975 1675);
FORCEPROP 1 LAST BODY_TYPE PLUMBING
J 0
(-2975 1725);
DISPLAY 1.446809 (-2975 1725);
PAINT GREEN (-2975 1725);
DISPLAY INVISIBLE (-2975 1725);
FORCEPROP 1 LAST HDL_TAP TRUE
J 0
(-2650 1550);
DISPLAY 1.446809 (-2650 1550);
PAINT GREEN (-2650 1550);
DISPLAY INVISIBLE (-2650 1550);
FORCEPROP 1 LAST PATH I46
J 0
(-2977 1675);
DISPLAY 0.872340 (-2977 1675);
PAINT GREEN (-2977 1675);
DISPLAY INVISIBLE (-2977 1675);
FORCEADD TAP..1
(-2975 1725);
FORCEPROP 3 LASTPIN (-3025 1725) SIG_NAME UPI_CPU0_CPU1_P1P1_DN<16>
J 0
(-3015 1735);
DISPLAY 0.659574 (-3015 1735);
PAINT MONO (-3015 1735);
DISPLAY INVISIBLE (-3015 1735);
FORCEPROP 1 LASTPIN (-3025 1725) BN 16
J 0
(-3037 1733);
DISPLAY 0.617021 (-3037 1733);
PAINT PINK (-3037 1733);
FORCEPROP 2 LAST CDS_LIB mstr_standard
J 0
(-2975 1725);
PAINT MONO (-2975 1725);
DISPLAY INVISIBLE (-2975 1725);
FORCEPROP 1 LAST BODY_TYPE PLUMBING
J 0
(-2975 1775);
DISPLAY 1.446809 (-2975 1775);
PAINT GREEN (-2975 1775);
DISPLAY INVISIBLE (-2975 1775);
FORCEPROP 1 LAST HDL_TAP TRUE
J 0
(-2650 1600);
DISPLAY 1.446809 (-2650 1600);
PAINT GREEN (-2650 1600);
DISPLAY INVISIBLE (-2650 1600);
FORCEPROP 1 LAST PATH I47
J 0
(-2977 1725);
DISPLAY 0.872340 (-2977 1725);
PAINT GREEN (-2977 1725);
DISPLAY INVISIBLE (-2977 1725);
FORCEADD TAP..1
(-2975 1775);
FORCEPROP 3 LASTPIN (-3025 1775) SIG_NAME UPI_CPU0_CPU1_P1P1_DN<15>
J 0
(-3015 1785);
DISPLAY 0.659574 (-3015 1785);
PAINT MONO (-3015 1785);
DISPLAY INVISIBLE (-3015 1785);
FORCEPROP 1 LASTPIN (-3025 1775) BN 15
J 0
(-3037 1783);
DISPLAY 0.617021 (-3037 1783);
PAINT PINK (-3037 1783);
FORCEPROP 2 LAST CDS_LIB mstr_standard
J 0
(-2975 1775);
PAINT MONO (-2975 1775);
DISPLAY INVISIBLE (-2975 1775);
FORCEPROP 1 LAST BODY_TYPE PLUMBING
J 0
(-2975 1825);
DISPLAY 1.446809 (-2975 1825);
PAINT GREEN (-2975 1825);
DISPLAY INVISIBLE (-2975 1825);
FORCEPROP 1 LAST HDL_TAP TRUE
J 0
(-2650 1650);
DISPLAY 1.446809 (-2650 1650);
PAINT GREEN (-2650 1650);
DISPLAY INVISIBLE (-2650 1650);
FORCEPROP 1 LAST PATH I48
J 0
(-2977 1775);
DISPLAY 0.872340 (-2977 1775);
PAINT GREEN (-2977 1775);
DISPLAY INVISIBLE (-2977 1775);
FORCEADD TAP..1
(-2975 1825);
FORCEPROP 3 LASTPIN (-3025 1825) SIG_NAME UPI_CPU0_CPU1_P1P1_DN<14>
J 0
(-3015 1835);
DISPLAY 0.659574 (-3015 1835);
PAINT MONO (-3015 1835);
DISPLAY INVISIBLE (-3015 1835);
FORCEPROP 1 LASTPIN (-3025 1825) BN 14
J 0
(-3037 1833);
DISPLAY 0.617021 (-3037 1833);
PAINT PINK (-3037 1833);
FORCEPROP 2 LAST CDS_LIB mstr_standard
J 0
(-2975 1825);
PAINT MONO (-2975 1825);
DISPLAY INVISIBLE (-2975 1825);
FORCEPROP 1 LAST BODY_TYPE PLUMBING
J 0
(-2975 1875);
DISPLAY 1.446809 (-2975 1875);
PAINT GREEN (-2975 1875);
DISPLAY INVISIBLE (-2975 1875);
FORCEPROP 1 LAST HDL_TAP TRUE
J 0
(-2650 1700);
DISPLAY 1.446809 (-2650 1700);
PAINT GREEN (-2650 1700);
DISPLAY INVISIBLE (-2650 1700);
FORCEPROP 1 LAST PATH I49
J 0
(-2977 1825);
DISPLAY 0.872340 (-2977 1825);
PAINT GREEN (-2977 1825);
DISPLAY INVISIBLE (-2977 1825);
FORCEADD TAP..1
R 2
(-5300 1675);
FORCEPROP 3 LASTPIN (-5250 1675) SIG_NAME UPI_CPU1_CPU0_P1P1_DN<17>
J 0
(-5240 1685);
DISPLAY 0.659574 (-5240 1685);
PAINT MONO (-5240 1685);
DISPLAY INVISIBLE (-5240 1685);
FORCEPROP 1 LASTPIN (-5250 1675) BN 17
J 2
(-5238 1683);
DISPLAY 0.617021 (-5238 1683);
PAINT PINK (-5238 1683);
FORCEPROP 2 LAST CDS_LIB mstr_standard
J 0
(-5300 1675);
PAINT MONO (-5300 1675);
DISPLAY INVISIBLE (-5300 1675);
FORCEPROP 1 LAST BODY_TYPE PLUMBING
J 2
(-5300 1725);
DISPLAY 1.446809 (-5300 1725);
PAINT GREEN (-5300 1725);
DISPLAY INVISIBLE (-5300 1725);
FORCEPROP 1 LAST HDL_TAP TRUE
J 2
(-5625 1550);
DISPLAY 1.446809 (-5625 1550);
PAINT GREEN (-5625 1550);
DISPLAY INVISIBLE (-5625 1550);
FORCEPROP 1 LAST PATH I5
J 2
(-5298 1675);
DISPLAY 0.872340 (-5298 1675);
PAINT GREEN (-5298 1675);
DISPLAY INVISIBLE (-5298 1675);
FORCEADD TAP..1
(-2975 1875);
FORCEPROP 3 LASTPIN (-3025 1875) SIG_NAME UPI_CPU0_CPU1_P1P1_DN<13>
J 0
(-3015 1885);
DISPLAY 0.659574 (-3015 1885);
PAINT MONO (-3015 1885);
DISPLAY INVISIBLE (-3015 1885);
FORCEPROP 1 LASTPIN (-3025 1875) BN 13
J 0
(-3037 1883);
DISPLAY 0.617021 (-3037 1883);
PAINT PINK (-3037 1883);
FORCEPROP 2 LAST CDS_LIB mstr_standard
J 0
(-2975 1875);
PAINT MONO (-2975 1875);
DISPLAY INVISIBLE (-2975 1875);
FORCEPROP 1 LAST BODY_TYPE PLUMBING
J 0
(-2975 1925);
DISPLAY 1.446809 (-2975 1925);
PAINT GREEN (-2975 1925);
DISPLAY INVISIBLE (-2975 1925);
FORCEPROP 1 LAST HDL_TAP TRUE
J 0
(-2650 1750);
DISPLAY 1.446809 (-2650 1750);
PAINT GREEN (-2650 1750);
DISPLAY INVISIBLE (-2650 1750);
FORCEPROP 1 LAST PATH I50
J 0
(-2977 1875);
DISPLAY 0.872340 (-2977 1875);
PAINT GREEN (-2977 1875);
DISPLAY INVISIBLE (-2977 1875);
FORCEADD TAP..1
(-2975 1925);
FORCEPROP 3 LASTPIN (-3025 1925) SIG_NAME UPI_CPU0_CPU1_P1P1_DN<12>
J 0
(-3015 1935);
DISPLAY 0.659574 (-3015 1935);
PAINT MONO (-3015 1935);
DISPLAY INVISIBLE (-3015 1935);
FORCEPROP 1 LASTPIN (-3025 1925) BN 12
J 0
(-3037 1933);
DISPLAY 0.617021 (-3037 1933);
PAINT PINK (-3037 1933);
FORCEPROP 2 LAST CDS_LIB mstr_standard
J 0
(-2975 1925);
PAINT MONO (-2975 1925);
DISPLAY INVISIBLE (-2975 1925);
FORCEPROP 1 LAST BODY_TYPE PLUMBING
J 0
(-2975 1975);
DISPLAY 1.446809 (-2975 1975);
PAINT GREEN (-2975 1975);
DISPLAY INVISIBLE (-2975 1975);
FORCEPROP 1 LAST HDL_TAP TRUE
J 0
(-2650 1800);
DISPLAY 1.446809 (-2650 1800);
PAINT GREEN (-2650 1800);
DISPLAY INVISIBLE (-2650 1800);
FORCEPROP 1 LAST PATH I51
J 0
(-2977 1925);
DISPLAY 0.872340 (-2977 1925);
PAINT GREEN (-2977 1925);
DISPLAY INVISIBLE (-2977 1925);
FORCEADD TAP..1
(-2975 1975);
FORCEPROP 3 LASTPIN (-3025 1975) SIG_NAME UPI_CPU0_CPU1_P1P1_DN<11>
J 0
(-3015 1985);
DISPLAY 0.659574 (-3015 1985);
PAINT MONO (-3015 1985);
DISPLAY INVISIBLE (-3015 1985);
FORCEPROP 1 LASTPIN (-3025 1975) BN 11
J 0
(-3037 1983);
DISPLAY 0.617021 (-3037 1983);
PAINT PINK (-3037 1983);
FORCEPROP 2 LAST CDS_LIB mstr_standard
J 0
(-2975 1975);
PAINT MONO (-2975 1975);
DISPLAY INVISIBLE (-2975 1975);
FORCEPROP 1 LAST BODY_TYPE PLUMBING
J 0
(-2975 2025);
DISPLAY 1.446809 (-2975 2025);
PAINT GREEN (-2975 2025);
DISPLAY INVISIBLE (-2975 2025);
FORCEPROP 1 LAST HDL_TAP TRUE
J 0
(-2650 1850);
DISPLAY 1.446809 (-2650 1850);
PAINT GREEN (-2650 1850);
DISPLAY INVISIBLE (-2650 1850);
FORCEPROP 1 LAST PATH I52
J 0
(-2977 1975);
DISPLAY 0.872340 (-2977 1975);
PAINT GREEN (-2977 1975);
DISPLAY INVISIBLE (-2977 1975);
FORCEADD TAP..1
(-2975 2025);
FORCEPROP 3 LASTPIN (-3025 2025) SIG_NAME UPI_CPU0_CPU1_P1P1_DN<10>
J 0
(-3015 2035);
DISPLAY 0.659574 (-3015 2035);
PAINT MONO (-3015 2035);
DISPLAY INVISIBLE (-3015 2035);
FORCEPROP 1 LASTPIN (-3025 2025) BN 10
J 0
(-3037 2033);
DISPLAY 0.617021 (-3037 2033);
PAINT PINK (-3037 2033);
FORCEPROP 2 LAST CDS_LIB mstr_standard
J 0
(-2975 2025);
PAINT MONO (-2975 2025);
DISPLAY INVISIBLE (-2975 2025);
FORCEPROP 1 LAST BODY_TYPE PLUMBING
J 0
(-2975 2075);
DISPLAY 1.446809 (-2975 2075);
PAINT GREEN (-2975 2075);
DISPLAY INVISIBLE (-2975 2075);
FORCEPROP 1 LAST HDL_TAP TRUE
J 0
(-2650 1900);
DISPLAY 1.446809 (-2650 1900);
PAINT GREEN (-2650 1900);
DISPLAY INVISIBLE (-2650 1900);
FORCEPROP 1 LAST PATH I53
J 0
(-2977 2025);
DISPLAY 0.872340 (-2977 2025);
PAINT GREEN (-2977 2025);
DISPLAY INVISIBLE (-2977 2025);
FORCEADD TAP..1
(-2975 2075);
FORCEPROP 3 LASTPIN (-3025 2075) SIG_NAME UPI_CPU0_CPU1_P1P1_DN<9>
J 0
(-3015 2085);
DISPLAY 0.659574 (-3015 2085);
PAINT MONO (-3015 2085);
DISPLAY INVISIBLE (-3015 2085);
FORCEPROP 1 LASTPIN (-3025 2075) BN 9
J 0
(-3037 2083);
DISPLAY 0.617021 (-3037 2083);
PAINT PINK (-3037 2083);
FORCEPROP 2 LAST CDS_LIB mstr_standard
J 0
(-2975 2075);
PAINT MONO (-2975 2075);
DISPLAY INVISIBLE (-2975 2075);
FORCEPROP 1 LAST BODY_TYPE PLUMBING
J 0
(-2975 2125);
DISPLAY 1.446809 (-2975 2125);
PAINT GREEN (-2975 2125);
DISPLAY INVISIBLE (-2975 2125);
FORCEPROP 1 LAST HDL_TAP TRUE
J 0
(-2650 1950);
DISPLAY 1.446809 (-2650 1950);
PAINT GREEN (-2650 1950);
DISPLAY INVISIBLE (-2650 1950);
FORCEPROP 1 LAST PATH I54
J 0
(-2977 2075);
DISPLAY 0.872340 (-2977 2075);
PAINT GREEN (-2977 2075);
DISPLAY INVISIBLE (-2977 2075);
FORCEADD TAP..1
(-2975 2125);
FORCEPROP 3 LASTPIN (-3025 2125) SIG_NAME UPI_CPU0_CPU1_P1P1_DN<8>
J 0
(-3015 2135);
DISPLAY 0.659574 (-3015 2135);
PAINT MONO (-3015 2135);
DISPLAY INVISIBLE (-3015 2135);
FORCEPROP 1 LASTPIN (-3025 2125) BN 8
J 0
(-3037 2133);
DISPLAY 0.617021 (-3037 2133);
PAINT PINK (-3037 2133);
FORCEPROP 2 LAST CDS_LIB mstr_standard
J 0
(-2975 2125);
PAINT MONO (-2975 2125);
DISPLAY INVISIBLE (-2975 2125);
FORCEPROP 1 LAST BODY_TYPE PLUMBING
J 0
(-2975 2175);
DISPLAY 1.446809 (-2975 2175);
PAINT GREEN (-2975 2175);
DISPLAY INVISIBLE (-2975 2175);
FORCEPROP 1 LAST HDL_TAP TRUE
J 0
(-2650 2000);
DISPLAY 1.446809 (-2650 2000);
PAINT GREEN (-2650 2000);
DISPLAY INVISIBLE (-2650 2000);
FORCEPROP 1 LAST PATH I55
J 0
(-2977 2125);
DISPLAY 0.872340 (-2977 2125);
PAINT GREEN (-2977 2125);
DISPLAY INVISIBLE (-2977 2125);
FORCEADD TAP..1
(-2975 2175);
FORCEPROP 3 LASTPIN (-3025 2175) SIG_NAME UPI_CPU0_CPU1_P1P1_DN<7>
J 0
(-3015 2185);
DISPLAY 0.659574 (-3015 2185);
PAINT MONO (-3015 2185);
DISPLAY INVISIBLE (-3015 2185);
FORCEPROP 1 LASTPIN (-3025 2175) BN 7
J 0
(-3037 2183);
DISPLAY 0.617021 (-3037 2183);
PAINT PINK (-3037 2183);
FORCEPROP 2 LAST CDS_LIB mstr_standard
J 0
(-2975 2175);
PAINT MONO (-2975 2175);
DISPLAY INVISIBLE (-2975 2175);
FORCEPROP 1 LAST BODY_TYPE PLUMBING
J 0
(-2975 2225);
DISPLAY 1.446809 (-2975 2225);
PAINT GREEN (-2975 2225);
DISPLAY INVISIBLE (-2975 2225);
FORCEPROP 1 LAST HDL_TAP TRUE
J 0
(-2650 2050);
DISPLAY 1.446809 (-2650 2050);
PAINT GREEN (-2650 2050);
DISPLAY INVISIBLE (-2650 2050);
FORCEPROP 1 LAST PATH I56
J 0
(-2977 2175);
DISPLAY 0.872340 (-2977 2175);
PAINT GREEN (-2977 2175);
DISPLAY INVISIBLE (-2977 2175);
FORCEADD TAP..1
(-2975 2225);
FORCEPROP 3 LASTPIN (-3025 2225) SIG_NAME UPI_CPU0_CPU1_P1P1_DN<6>
J 0
(-3015 2235);
DISPLAY 0.659574 (-3015 2235);
PAINT MONO (-3015 2235);
DISPLAY INVISIBLE (-3015 2235);
FORCEPROP 1 LASTPIN (-3025 2225) BN 6
J 0
(-3037 2233);
DISPLAY 0.617021 (-3037 2233);
PAINT PINK (-3037 2233);
FORCEPROP 2 LAST CDS_LIB mstr_standard
J 0
(-2975 2225);
PAINT MONO (-2975 2225);
DISPLAY INVISIBLE (-2975 2225);
FORCEPROP 1 LAST BODY_TYPE PLUMBING
J 0
(-2975 2275);
DISPLAY 1.446809 (-2975 2275);
PAINT GREEN (-2975 2275);
DISPLAY INVISIBLE (-2975 2275);
FORCEPROP 1 LAST HDL_TAP TRUE
J 0
(-2650 2100);
DISPLAY 1.446809 (-2650 2100);
PAINT GREEN (-2650 2100);
DISPLAY INVISIBLE (-2650 2100);
FORCEPROP 1 LAST PATH I57
J 0
(-2977 2225);
DISPLAY 0.872340 (-2977 2225);
PAINT GREEN (-2977 2225);
DISPLAY INVISIBLE (-2977 2225);
FORCEADD TAP..1
(-2975 2275);
FORCEPROP 3 LASTPIN (-3025 2275) SIG_NAME UPI_CPU0_CPU1_P1P1_DN<5>
J 0
(-3015 2285);
DISPLAY 0.659574 (-3015 2285);
PAINT MONO (-3015 2285);
DISPLAY INVISIBLE (-3015 2285);
FORCEPROP 1 LASTPIN (-3025 2275) BN 5
J 0
(-3037 2283);
DISPLAY 0.617021 (-3037 2283);
PAINT PINK (-3037 2283);
FORCEPROP 2 LAST CDS_LIB mstr_standard
J 0
(-2975 2275);
PAINT MONO (-2975 2275);
DISPLAY INVISIBLE (-2975 2275);
FORCEPROP 1 LAST BODY_TYPE PLUMBING
J 0
(-2975 2325);
DISPLAY 1.446809 (-2975 2325);
PAINT GREEN (-2975 2325);
DISPLAY INVISIBLE (-2975 2325);
FORCEPROP 1 LAST HDL_TAP TRUE
J 0
(-2650 2150);
DISPLAY 1.446809 (-2650 2150);
PAINT GREEN (-2650 2150);
DISPLAY INVISIBLE (-2650 2150);
FORCEPROP 1 LAST PATH I58
J 0
(-2977 2275);
DISPLAY 0.872340 (-2977 2275);
PAINT GREEN (-2977 2275);
DISPLAY INVISIBLE (-2977 2275);
FORCEADD TAP..1
(-2975 2325);
FORCEPROP 3 LASTPIN (-3025 2325) SIG_NAME UPI_CPU0_CPU1_P1P1_DN<4>
J 0
(-3015 2335);
DISPLAY 0.659574 (-3015 2335);
PAINT MONO (-3015 2335);
DISPLAY INVISIBLE (-3015 2335);
FORCEPROP 1 LASTPIN (-3025 2325) BN 4
J 0
(-3037 2333);
DISPLAY 0.617021 (-3037 2333);
PAINT PINK (-3037 2333);
FORCEPROP 2 LAST CDS_LIB mstr_standard
J 0
(-2975 2325);
PAINT MONO (-2975 2325);
DISPLAY INVISIBLE (-2975 2325);
FORCEPROP 1 LAST BODY_TYPE PLUMBING
J 0
(-2975 2375);
DISPLAY 1.446809 (-2975 2375);
PAINT GREEN (-2975 2375);
DISPLAY INVISIBLE (-2975 2375);
FORCEPROP 1 LAST HDL_TAP TRUE
J 0
(-2650 2200);
DISPLAY 1.446809 (-2650 2200);
PAINT GREEN (-2650 2200);
DISPLAY INVISIBLE (-2650 2200);
FORCEPROP 1 LAST PATH I59
J 0
(-2977 2325);
DISPLAY 0.872340 (-2977 2325);
PAINT GREEN (-2977 2325);
DISPLAY INVISIBLE (-2977 2325);
FORCEADD TAP..1
R 2
(-5300 1725);
FORCEPROP 3 LASTPIN (-5250 1725) SIG_NAME UPI_CPU1_CPU0_P1P1_DN<16>
J 0
(-5240 1735);
DISPLAY 0.659574 (-5240 1735);
PAINT MONO (-5240 1735);
DISPLAY INVISIBLE (-5240 1735);
FORCEPROP 1 LASTPIN (-5250 1725) BN 16
J 2
(-5238 1733);
DISPLAY 0.617021 (-5238 1733);
PAINT PINK (-5238 1733);
FORCEPROP 2 LAST CDS_LIB mstr_standard
J 0
(-5300 1725);
PAINT MONO (-5300 1725);
DISPLAY INVISIBLE (-5300 1725);
FORCEPROP 1 LAST BODY_TYPE PLUMBING
J 2
(-5300 1775);
DISPLAY 1.446809 (-5300 1775);
PAINT GREEN (-5300 1775);
DISPLAY INVISIBLE (-5300 1775);
FORCEPROP 1 LAST HDL_TAP TRUE
J 2
(-5625 1600);
DISPLAY 1.446809 (-5625 1600);
PAINT GREEN (-5625 1600);
DISPLAY INVISIBLE (-5625 1600);
FORCEPROP 1 LAST PATH I6
J 2
(-5298 1725);
DISPLAY 0.872340 (-5298 1725);
PAINT GREEN (-5298 1725);
DISPLAY INVISIBLE (-5298 1725);
FORCEADD TAP..1
(-2975 2375);
FORCEPROP 3 LASTPIN (-3025 2375) SIG_NAME UPI_CPU0_CPU1_P1P1_DN<3>
J 0
(-3015 2385);
DISPLAY 0.659574 (-3015 2385);
PAINT MONO (-3015 2385);
DISPLAY INVISIBLE (-3015 2385);
FORCEPROP 1 LASTPIN (-3025 2375) BN 3
J 0
(-3037 2383);
DISPLAY 0.617021 (-3037 2383);
PAINT PINK (-3037 2383);
FORCEPROP 2 LAST CDS_LIB mstr_standard
J 0
(-2975 2375);
PAINT MONO (-2975 2375);
DISPLAY INVISIBLE (-2975 2375);
FORCEPROP 1 LAST BODY_TYPE PLUMBING
J 0
(-2975 2425);
DISPLAY 1.446809 (-2975 2425);
PAINT GREEN (-2975 2425);
DISPLAY INVISIBLE (-2975 2425);
FORCEPROP 1 LAST HDL_TAP TRUE
J 0
(-2650 2250);
DISPLAY 1.446809 (-2650 2250);
PAINT GREEN (-2650 2250);
DISPLAY INVISIBLE (-2650 2250);
FORCEPROP 1 LAST PATH I60
J 0
(-2977 2375);
DISPLAY 0.872340 (-2977 2375);
PAINT GREEN (-2977 2375);
DISPLAY INVISIBLE (-2977 2375);
FORCEADD TAP..1
(-2975 2425);
FORCEPROP 3 LASTPIN (-3025 2425) SIG_NAME UPI_CPU0_CPU1_P1P1_DN<2>
J 0
(-3015 2435);
DISPLAY 0.659574 (-3015 2435);
PAINT MONO (-3015 2435);
DISPLAY INVISIBLE (-3015 2435);
FORCEPROP 1 LASTPIN (-3025 2425) BN 2
J 0
(-3037 2433);
DISPLAY 0.617021 (-3037 2433);
PAINT PINK (-3037 2433);
FORCEPROP 2 LAST CDS_LIB mstr_standard
J 0
(-2975 2425);
PAINT MONO (-2975 2425);
DISPLAY INVISIBLE (-2975 2425);
FORCEPROP 1 LAST BODY_TYPE PLUMBING
J 0
(-2975 2475);
DISPLAY 1.446809 (-2975 2475);
PAINT GREEN (-2975 2475);
DISPLAY INVISIBLE (-2975 2475);
FORCEPROP 1 LAST HDL_TAP TRUE
J 0
(-2650 2300);
DISPLAY 1.446809 (-2650 2300);
PAINT GREEN (-2650 2300);
DISPLAY INVISIBLE (-2650 2300);
FORCEPROP 1 LAST PATH I61
J 0
(-2977 2425);
DISPLAY 0.872340 (-2977 2425);
PAINT GREEN (-2977 2425);
DISPLAY INVISIBLE (-2977 2425);
FORCEADD TAP..1
(-2975 2475);
FORCEPROP 3 LASTPIN (-3025 2475) SIG_NAME UPI_CPU0_CPU1_P1P1_DN<1>
J 0
(-3015 2485);
DISPLAY 0.659574 (-3015 2485);
PAINT MONO (-3015 2485);
DISPLAY INVISIBLE (-3015 2485);
FORCEPROP 1 LASTPIN (-3025 2475) BN 1
J 0
(-3037 2483);
DISPLAY 0.617021 (-3037 2483);
PAINT PINK (-3037 2483);
FORCEPROP 2 LAST CDS_LIB mstr_standard
J 0
(-2975 2475);
PAINT MONO (-2975 2475);
DISPLAY INVISIBLE (-2975 2475);
FORCEPROP 1 LAST BODY_TYPE PLUMBING
J 0
(-2975 2525);
DISPLAY 1.446809 (-2975 2525);
PAINT GREEN (-2975 2525);
DISPLAY INVISIBLE (-2975 2525);
FORCEPROP 1 LAST HDL_TAP TRUE
J 0
(-2650 2350);
DISPLAY 1.446809 (-2650 2350);
PAINT GREEN (-2650 2350);
DISPLAY INVISIBLE (-2650 2350);
FORCEPROP 1 LAST PATH I62
J 0
(-2977 2475);
DISPLAY 0.872340 (-2977 2475);
PAINT GREEN (-2977 2475);
DISPLAY INVISIBLE (-2977 2475);
FORCEADD TAP..1
(-2975 2525);
FORCEPROP 3 LASTPIN (-3025 2525) SIG_NAME UPI_CPU0_CPU1_P1P1_DN<0>
J 0
(-3015 2535);
DISPLAY 0.659574 (-3015 2535);
PAINT MONO (-3015 2535);
DISPLAY INVISIBLE (-3015 2535);
FORCEPROP 1 LASTPIN (-3025 2525) BN 0
J 0
(-3037 2533);
DISPLAY 0.617021 (-3037 2533);
PAINT PINK (-3037 2533);
FORCEPROP 2 LAST CDS_LIB mstr_standard
J 0
(-2975 2525);
PAINT MONO (-2975 2525);
DISPLAY INVISIBLE (-2975 2525);
FORCEPROP 1 LAST BODY_TYPE PLUMBING
J 0
(-2975 2575);
DISPLAY 1.446809 (-2975 2575);
PAINT GREEN (-2975 2575);
DISPLAY INVISIBLE (-2975 2575);
FORCEPROP 1 LAST HDL_TAP TRUE
J 0
(-2650 2400);
DISPLAY 1.446809 (-2650 2400);
PAINT GREEN (-2650 2400);
DISPLAY INVISIBLE (-2650 2400);
FORCEPROP 1 LAST PATH I63
J 0
(-2977 2525);
DISPLAY 0.872340 (-2977 2525);
PAINT GREEN (-2977 2525);
DISPLAY INVISIBLE (-2977 2525);
FORCEADD TAP..1
(-2975 2625);
FORCEPROP 3 LASTPIN (-3025 2625) SIG_NAME UPI_CPU0_CPU1_P1P1_DP<19>
J 0
(-3015 2635);
DISPLAY 0.659574 (-3015 2635);
PAINT MONO (-3015 2635);
DISPLAY INVISIBLE (-3015 2635);
FORCEPROP 1 LASTPIN (-3025 2625) BN 19
J 0
(-3037 2633);
DISPLAY 0.617021 (-3037 2633);
PAINT PINK (-3037 2633);
FORCEPROP 2 LAST CDS_LIB mstr_standard
J 0
(-2975 2625);
PAINT MONO (-2975 2625);
DISPLAY INVISIBLE (-2975 2625);
FORCEPROP 1 LAST BODY_TYPE PLUMBING
J 0
(-2975 2675);
DISPLAY 1.446809 (-2975 2675);
PAINT GREEN (-2975 2675);
DISPLAY INVISIBLE (-2975 2675);
FORCEPROP 1 LAST HDL_TAP TRUE
J 0
(-2650 2500);
DISPLAY 1.446809 (-2650 2500);
PAINT GREEN (-2650 2500);
DISPLAY INVISIBLE (-2650 2500);
FORCEPROP 1 LAST PATH I64
J 0
(-2977 2625);
DISPLAY 0.872340 (-2977 2625);
PAINT GREEN (-2977 2625);
DISPLAY INVISIBLE (-2977 2625);
FORCEADD TAP..1
(-2975 2675);
FORCEPROP 3 LASTPIN (-3025 2675) SIG_NAME UPI_CPU0_CPU1_P1P1_DP<18>
J 0
(-3015 2685);
DISPLAY 0.659574 (-3015 2685);
PAINT MONO (-3015 2685);
DISPLAY INVISIBLE (-3015 2685);
FORCEPROP 1 LASTPIN (-3025 2675) BN 18
J 0
(-3037 2683);
DISPLAY 0.617021 (-3037 2683);
PAINT PINK (-3037 2683);
FORCEPROP 2 LAST CDS_LIB mstr_standard
J 0
(-2975 2675);
PAINT MONO (-2975 2675);
DISPLAY INVISIBLE (-2975 2675);
FORCEPROP 1 LAST BODY_TYPE PLUMBING
J 0
(-2975 2725);
DISPLAY 1.446809 (-2975 2725);
PAINT GREEN (-2975 2725);
DISPLAY INVISIBLE (-2975 2725);
FORCEPROP 1 LAST HDL_TAP TRUE
J 0
(-2650 2550);
DISPLAY 1.446809 (-2650 2550);
PAINT GREEN (-2650 2550);
DISPLAY INVISIBLE (-2650 2550);
FORCEPROP 1 LAST PATH I65
J 0
(-2977 2675);
DISPLAY 0.872340 (-2977 2675);
PAINT GREEN (-2977 2675);
DISPLAY INVISIBLE (-2977 2675);
FORCEADD TAP..1
(-2975 2725);
FORCEPROP 3 LASTPIN (-3025 2725) SIG_NAME UPI_CPU0_CPU1_P1P1_DP<17>
J 0
(-3015 2735);
DISPLAY 0.659574 (-3015 2735);
PAINT MONO (-3015 2735);
DISPLAY INVISIBLE (-3015 2735);
FORCEPROP 1 LASTPIN (-3025 2725) BN 17
J 0
(-3037 2733);
DISPLAY 0.617021 (-3037 2733);
PAINT PINK (-3037 2733);
FORCEPROP 2 LAST CDS_LIB mstr_standard
J 0
(-2975 2725);
PAINT MONO (-2975 2725);
DISPLAY INVISIBLE (-2975 2725);
FORCEPROP 1 LAST BODY_TYPE PLUMBING
J 0
(-2975 2775);
DISPLAY 1.446809 (-2975 2775);
PAINT GREEN (-2975 2775);
DISPLAY INVISIBLE (-2975 2775);
FORCEPROP 1 LAST HDL_TAP TRUE
J 0
(-2650 2600);
DISPLAY 1.446809 (-2650 2600);
PAINT GREEN (-2650 2600);
DISPLAY INVISIBLE (-2650 2600);
FORCEPROP 1 LAST PATH I66
J 0
(-2977 2725);
DISPLAY 0.872340 (-2977 2725);
PAINT GREEN (-2977 2725);
DISPLAY INVISIBLE (-2977 2725);
FORCEADD TAP..1
(-2975 2775);
FORCEPROP 3 LASTPIN (-3025 2775) SIG_NAME UPI_CPU0_CPU1_P1P1_DP<16>
J 0
(-3015 2785);
DISPLAY 0.659574 (-3015 2785);
PAINT MONO (-3015 2785);
DISPLAY INVISIBLE (-3015 2785);
FORCEPROP 1 LASTPIN (-3025 2775) BN 16
J 0
(-3037 2783);
DISPLAY 0.617021 (-3037 2783);
PAINT PINK (-3037 2783);
FORCEPROP 2 LAST CDS_LIB mstr_standard
J 0
(-2975 2775);
PAINT MONO (-2975 2775);
DISPLAY INVISIBLE (-2975 2775);
FORCEPROP 1 LAST BODY_TYPE PLUMBING
J 0
(-2975 2825);
DISPLAY 1.446809 (-2975 2825);
PAINT GREEN (-2975 2825);
DISPLAY INVISIBLE (-2975 2825);
FORCEPROP 1 LAST HDL_TAP TRUE
J 0
(-2650 2650);
DISPLAY 1.446809 (-2650 2650);
PAINT GREEN (-2650 2650);
DISPLAY INVISIBLE (-2650 2650);
FORCEPROP 1 LAST PATH I67
J 0
(-2977 2775);
DISPLAY 0.872340 (-2977 2775);
PAINT GREEN (-2977 2775);
DISPLAY INVISIBLE (-2977 2775);
FORCEADD TAP..1
(-2975 2825);
FORCEPROP 3 LASTPIN (-3025 2825) SIG_NAME UPI_CPU0_CPU1_P1P1_DP<15>
J 0
(-3015 2835);
DISPLAY 0.659574 (-3015 2835);
PAINT MONO (-3015 2835);
DISPLAY INVISIBLE (-3015 2835);
FORCEPROP 1 LASTPIN (-3025 2825) BN 15
J 0
(-3037 2833);
DISPLAY 0.617021 (-3037 2833);
PAINT PINK (-3037 2833);
FORCEPROP 2 LAST CDS_LIB mstr_standard
J 0
(-2975 2825);
PAINT MONO (-2975 2825);
DISPLAY INVISIBLE (-2975 2825);
FORCEPROP 1 LAST BODY_TYPE PLUMBING
J 0
(-2975 2875);
DISPLAY 1.446809 (-2975 2875);
PAINT GREEN (-2975 2875);
DISPLAY INVISIBLE (-2975 2875);
FORCEPROP 1 LAST HDL_TAP TRUE
J 0
(-2650 2700);
DISPLAY 1.446809 (-2650 2700);
PAINT GREEN (-2650 2700);
DISPLAY INVISIBLE (-2650 2700);
FORCEPROP 1 LAST PATH I68
J 0
(-2977 2825);
DISPLAY 0.872340 (-2977 2825);
PAINT GREEN (-2977 2825);
DISPLAY INVISIBLE (-2977 2825);
FORCEADD TAP..1
(-2975 2875);
FORCEPROP 3 LASTPIN (-3025 2875) SIG_NAME UPI_CPU0_CPU1_P1P1_DP<14>
J 0
(-3015 2885);
DISPLAY 0.659574 (-3015 2885);
PAINT MONO (-3015 2885);
DISPLAY INVISIBLE (-3015 2885);
FORCEPROP 1 LASTPIN (-3025 2875) BN 14
J 0
(-3037 2883);
DISPLAY 0.617021 (-3037 2883);
PAINT PINK (-3037 2883);
FORCEPROP 2 LAST CDS_LIB mstr_standard
J 0
(-2975 2875);
PAINT MONO (-2975 2875);
DISPLAY INVISIBLE (-2975 2875);
FORCEPROP 1 LAST BODY_TYPE PLUMBING
J 0
(-2975 2925);
DISPLAY 1.446809 (-2975 2925);
PAINT GREEN (-2975 2925);
DISPLAY INVISIBLE (-2975 2925);
FORCEPROP 1 LAST HDL_TAP TRUE
J 0
(-2650 2750);
DISPLAY 1.446809 (-2650 2750);
PAINT GREEN (-2650 2750);
DISPLAY INVISIBLE (-2650 2750);
FORCEPROP 1 LAST PATH I69
J 0
(-2977 2875);
DISPLAY 0.872340 (-2977 2875);
PAINT GREEN (-2977 2875);
DISPLAY INVISIBLE (-2977 2875);
FORCEADD TAP..1
R 2
(-5300 1775);
FORCEPROP 3 LASTPIN (-5250 1775) SIG_NAME UPI_CPU1_CPU0_P1P1_DN<15>
J 0
(-5240 1785);
DISPLAY 0.659574 (-5240 1785);
PAINT MONO (-5240 1785);
DISPLAY INVISIBLE (-5240 1785);
FORCEPROP 1 LASTPIN (-5250 1775) BN 15
J 2
(-5238 1783);
DISPLAY 0.617021 (-5238 1783);
PAINT PINK (-5238 1783);
FORCEPROP 2 LAST CDS_LIB mstr_standard
J 0
(-5300 1775);
PAINT MONO (-5300 1775);
DISPLAY INVISIBLE (-5300 1775);
FORCEPROP 1 LAST BODY_TYPE PLUMBING
J 2
(-5300 1825);
DISPLAY 1.446809 (-5300 1825);
PAINT GREEN (-5300 1825);
DISPLAY INVISIBLE (-5300 1825);
FORCEPROP 1 LAST HDL_TAP TRUE
J 2
(-5625 1650);
DISPLAY 1.446809 (-5625 1650);
PAINT GREEN (-5625 1650);
DISPLAY INVISIBLE (-5625 1650);
FORCEPROP 1 LAST PATH I7
J 2
(-5298 1775);
DISPLAY 0.872340 (-5298 1775);
PAINT GREEN (-5298 1775);
DISPLAY INVISIBLE (-5298 1775);
FORCEADD TAP..1
(-2975 2925);
FORCEPROP 3 LASTPIN (-3025 2925) SIG_NAME UPI_CPU0_CPU1_P1P1_DP<13>
J 0
(-3015 2935);
DISPLAY 0.659574 (-3015 2935);
PAINT MONO (-3015 2935);
DISPLAY INVISIBLE (-3015 2935);
FORCEPROP 1 LASTPIN (-3025 2925) BN 13
J 0
(-3037 2933);
DISPLAY 0.617021 (-3037 2933);
PAINT PINK (-3037 2933);
FORCEPROP 2 LAST CDS_LIB mstr_standard
J 0
(-2975 2925);
PAINT MONO (-2975 2925);
DISPLAY INVISIBLE (-2975 2925);
FORCEPROP 1 LAST BODY_TYPE PLUMBING
J 0
(-2975 2975);
DISPLAY 1.446809 (-2975 2975);
PAINT GREEN (-2975 2975);
DISPLAY INVISIBLE (-2975 2975);
FORCEPROP 1 LAST HDL_TAP TRUE
J 0
(-2650 2800);
DISPLAY 1.446809 (-2650 2800);
PAINT GREEN (-2650 2800);
DISPLAY INVISIBLE (-2650 2800);
FORCEPROP 1 LAST PATH I70
J 0
(-2977 2925);
DISPLAY 0.872340 (-2977 2925);
PAINT GREEN (-2977 2925);
DISPLAY INVISIBLE (-2977 2925);
FORCEADD TAP..1
(-2975 2975);
FORCEPROP 3 LASTPIN (-3025 2975) SIG_NAME UPI_CPU0_CPU1_P1P1_DP<12>
J 0
(-3015 2985);
DISPLAY 0.659574 (-3015 2985);
PAINT MONO (-3015 2985);
DISPLAY INVISIBLE (-3015 2985);
FORCEPROP 1 LASTPIN (-3025 2975) BN 12
J 0
(-3037 2983);
DISPLAY 0.617021 (-3037 2983);
PAINT PINK (-3037 2983);
FORCEPROP 2 LAST CDS_LIB mstr_standard
J 0
(-2975 2975);
PAINT MONO (-2975 2975);
DISPLAY INVISIBLE (-2975 2975);
FORCEPROP 1 LAST BODY_TYPE PLUMBING
J 0
(-2975 3025);
DISPLAY 1.446809 (-2975 3025);
PAINT GREEN (-2975 3025);
DISPLAY INVISIBLE (-2975 3025);
FORCEPROP 1 LAST HDL_TAP TRUE
J 0
(-2650 2850);
DISPLAY 1.446809 (-2650 2850);
PAINT GREEN (-2650 2850);
DISPLAY INVISIBLE (-2650 2850);
FORCEPROP 1 LAST PATH I71
J 0
(-2977 2975);
DISPLAY 0.872340 (-2977 2975);
PAINT GREEN (-2977 2975);
DISPLAY INVISIBLE (-2977 2975);
FORCEADD TAP..1
(-2975 3025);
FORCEPROP 3 LASTPIN (-3025 3025) SIG_NAME UPI_CPU0_CPU1_P1P1_DP<11>
J 0
(-3015 3035);
DISPLAY 0.659574 (-3015 3035);
PAINT MONO (-3015 3035);
DISPLAY INVISIBLE (-3015 3035);
FORCEPROP 1 LASTPIN (-3025 3025) BN 11
J 0
(-3037 3033);
DISPLAY 0.617021 (-3037 3033);
PAINT PINK (-3037 3033);
FORCEPROP 2 LAST CDS_LIB mstr_standard
J 0
(-2975 3025);
PAINT MONO (-2975 3025);
DISPLAY INVISIBLE (-2975 3025);
FORCEPROP 1 LAST BODY_TYPE PLUMBING
J 0
(-2975 3075);
DISPLAY 1.446809 (-2975 3075);
PAINT GREEN (-2975 3075);
DISPLAY INVISIBLE (-2975 3075);
FORCEPROP 1 LAST HDL_TAP TRUE
J 0
(-2650 2900);
DISPLAY 1.446809 (-2650 2900);
PAINT GREEN (-2650 2900);
DISPLAY INVISIBLE (-2650 2900);
FORCEPROP 1 LAST PATH I72
J 0
(-2977 3025);
DISPLAY 0.872340 (-2977 3025);
PAINT GREEN (-2977 3025);
DISPLAY INVISIBLE (-2977 3025);
FORCEADD TAP..1
(-2975 3075);
FORCEPROP 3 LASTPIN (-3025 3075) SIG_NAME UPI_CPU0_CPU1_P1P1_DP<10>
J 0
(-3015 3085);
DISPLAY 0.659574 (-3015 3085);
PAINT MONO (-3015 3085);
DISPLAY INVISIBLE (-3015 3085);
FORCEPROP 1 LASTPIN (-3025 3075) BN 10
J 0
(-3037 3083);
DISPLAY 0.617021 (-3037 3083);
PAINT PINK (-3037 3083);
FORCEPROP 2 LAST CDS_LIB mstr_standard
J 0
(-2975 3075);
PAINT MONO (-2975 3075);
DISPLAY INVISIBLE (-2975 3075);
FORCEPROP 1 LAST BODY_TYPE PLUMBING
J 0
(-2975 3125);
DISPLAY 1.446809 (-2975 3125);
PAINT GREEN (-2975 3125);
DISPLAY INVISIBLE (-2975 3125);
FORCEPROP 1 LAST HDL_TAP TRUE
J 0
(-2650 2950);
DISPLAY 1.446809 (-2650 2950);
PAINT GREEN (-2650 2950);
DISPLAY INVISIBLE (-2650 2950);
FORCEPROP 1 LAST PATH I73
J 0
(-2977 3075);
DISPLAY 0.872340 (-2977 3075);
PAINT GREEN (-2977 3075);
DISPLAY INVISIBLE (-2977 3075);
FORCEADD TAP..1
(-2975 3125);
FORCEPROP 3 LASTPIN (-3025 3125) SIG_NAME UPI_CPU0_CPU1_P1P1_DP<9>
J 0
(-3015 3135);
DISPLAY 0.659574 (-3015 3135);
PAINT MONO (-3015 3135);
DISPLAY INVISIBLE (-3015 3135);
FORCEPROP 1 LASTPIN (-3025 3125) BN 9
J 0
(-3037 3133);
DISPLAY 0.617021 (-3037 3133);
PAINT PINK (-3037 3133);
FORCEPROP 2 LAST CDS_LIB mstr_standard
J 0
(-2975 3125);
PAINT MONO (-2975 3125);
DISPLAY INVISIBLE (-2975 3125);
FORCEPROP 1 LAST BODY_TYPE PLUMBING
J 0
(-2975 3175);
DISPLAY 1.446809 (-2975 3175);
PAINT GREEN (-2975 3175);
DISPLAY INVISIBLE (-2975 3175);
FORCEPROP 1 LAST HDL_TAP TRUE
J 0
(-2650 3000);
DISPLAY 1.446809 (-2650 3000);
PAINT GREEN (-2650 3000);
DISPLAY INVISIBLE (-2650 3000);
FORCEPROP 1 LAST PATH I74
J 0
(-2977 3125);
DISPLAY 0.872340 (-2977 3125);
PAINT GREEN (-2977 3125);
DISPLAY INVISIBLE (-2977 3125);
FORCEADD TAP..1
(-2975 3225);
FORCEPROP 3 LASTPIN (-3025 3225) SIG_NAME UPI_CPU0_CPU1_P1P1_DP<7>
J 0
(-3015 3235);
DISPLAY 0.659574 (-3015 3235);
PAINT MONO (-3015 3235);
DISPLAY INVISIBLE (-3015 3235);
FORCEPROP 1 LASTPIN (-3025 3225) BN 7
J 0
(-3037 3233);
DISPLAY 0.617021 (-3037 3233);
PAINT PINK (-3037 3233);
FORCEPROP 2 LAST CDS_LIB mstr_standard
J 0
(-2975 3225);
PAINT MONO (-2975 3225);
DISPLAY INVISIBLE (-2975 3225);
FORCEPROP 1 LAST BODY_TYPE PLUMBING
J 0
(-2975 3275);
DISPLAY 1.446809 (-2975 3275);
PAINT GREEN (-2975 3275);
DISPLAY INVISIBLE (-2975 3275);
FORCEPROP 1 LAST HDL_TAP TRUE
J 0
(-2650 3100);
DISPLAY 1.446809 (-2650 3100);
PAINT GREEN (-2650 3100);
DISPLAY INVISIBLE (-2650 3100);
FORCEPROP 1 LAST PATH I75
J 0
(-2977 3225);
DISPLAY 0.872340 (-2977 3225);
PAINT GREEN (-2977 3225);
DISPLAY INVISIBLE (-2977 3225);
FORCEADD TAP..1
(-2975 3175);
FORCEPROP 3 LASTPIN (-3025 3175) SIG_NAME UPI_CPU0_CPU1_P1P1_DP<8>
J 0
(-3015 3185);
DISPLAY 0.659574 (-3015 3185);
PAINT MONO (-3015 3185);
DISPLAY INVISIBLE (-3015 3185);
FORCEPROP 1 LASTPIN (-3025 3175) BN 8
J 0
(-3037 3183);
DISPLAY 0.617021 (-3037 3183);
PAINT PINK (-3037 3183);
FORCEPROP 2 LAST CDS_LIB mstr_standard
J 0
(-2975 3175);
PAINT MONO (-2975 3175);
DISPLAY INVISIBLE (-2975 3175);
FORCEPROP 1 LAST BODY_TYPE PLUMBING
J 0
(-2975 3225);
DISPLAY 1.446809 (-2975 3225);
PAINT GREEN (-2975 3225);
DISPLAY INVISIBLE (-2975 3225);
FORCEPROP 1 LAST HDL_TAP TRUE
J 0
(-2650 3050);
DISPLAY 1.446809 (-2650 3050);
PAINT GREEN (-2650 3050);
DISPLAY INVISIBLE (-2650 3050);
FORCEPROP 1 LAST PATH I76
J 0
(-2977 3175);
DISPLAY 0.872340 (-2977 3175);
PAINT GREEN (-2977 3175);
DISPLAY INVISIBLE (-2977 3175);
FORCEADD TAP..1
(-2975 3275);
FORCEPROP 3 LASTPIN (-3025 3275) SIG_NAME UPI_CPU0_CPU1_P1P1_DP<6>
J 0
(-3015 3285);
DISPLAY 0.659574 (-3015 3285);
PAINT MONO (-3015 3285);
DISPLAY INVISIBLE (-3015 3285);
FORCEPROP 1 LASTPIN (-3025 3275) BN 6
J 0
(-3037 3283);
DISPLAY 0.617021 (-3037 3283);
PAINT PINK (-3037 3283);
FORCEPROP 2 LAST CDS_LIB mstr_standard
J 0
(-2975 3275);
PAINT MONO (-2975 3275);
DISPLAY INVISIBLE (-2975 3275);
FORCEPROP 1 LAST BODY_TYPE PLUMBING
J 0
(-2975 3325);
DISPLAY 1.446809 (-2975 3325);
PAINT GREEN (-2975 3325);
DISPLAY INVISIBLE (-2975 3325);
FORCEPROP 1 LAST HDL_TAP TRUE
J 0
(-2650 3150);
DISPLAY 1.446809 (-2650 3150);
PAINT GREEN (-2650 3150);
DISPLAY INVISIBLE (-2650 3150);
FORCEPROP 1 LAST PATH I77
J 0
(-2977 3275);
DISPLAY 0.872340 (-2977 3275);
PAINT GREEN (-2977 3275);
DISPLAY INVISIBLE (-2977 3275);
FORCEADD TAP..1
(-2975 3325);
FORCEPROP 3 LASTPIN (-3025 3325) SIG_NAME UPI_CPU0_CPU1_P1P1_DP<5>
J 0
(-3015 3335);
DISPLAY 0.659574 (-3015 3335);
PAINT MONO (-3015 3335);
DISPLAY INVISIBLE (-3015 3335);
FORCEPROP 1 LASTPIN (-3025 3325) BN 5
J 0
(-3037 3333);
DISPLAY 0.617021 (-3037 3333);
PAINT PINK (-3037 3333);
FORCEPROP 2 LAST CDS_LIB mstr_standard
J 0
(-2975 3325);
PAINT MONO (-2975 3325);
DISPLAY INVISIBLE (-2975 3325);
FORCEPROP 1 LAST BODY_TYPE PLUMBING
J 0
(-2975 3375);
DISPLAY 1.446809 (-2975 3375);
PAINT GREEN (-2975 3375);
DISPLAY INVISIBLE (-2975 3375);
FORCEPROP 1 LAST HDL_TAP TRUE
J 0
(-2650 3200);
DISPLAY 1.446809 (-2650 3200);
PAINT GREEN (-2650 3200);
DISPLAY INVISIBLE (-2650 3200);
FORCEPROP 1 LAST PATH I78
J 0
(-2977 3325);
DISPLAY 0.872340 (-2977 3325);
PAINT GREEN (-2977 3325);
DISPLAY INVISIBLE (-2977 3325);
FORCEADD TAP..1
(-2975 3375);
FORCEPROP 3 LASTPIN (-3025 3375) SIG_NAME UPI_CPU0_CPU1_P1P1_DP<4>
J 0
(-3015 3385);
DISPLAY 0.659574 (-3015 3385);
PAINT MONO (-3015 3385);
DISPLAY INVISIBLE (-3015 3385);
FORCEPROP 1 LASTPIN (-3025 3375) BN 4
J 0
(-3037 3383);
DISPLAY 0.617021 (-3037 3383);
PAINT PINK (-3037 3383);
FORCEPROP 2 LAST CDS_LIB mstr_standard
J 0
(-2975 3375);
PAINT MONO (-2975 3375);
DISPLAY INVISIBLE (-2975 3375);
FORCEPROP 1 LAST BODY_TYPE PLUMBING
J 0
(-2975 3425);
DISPLAY 1.446809 (-2975 3425);
PAINT GREEN (-2975 3425);
DISPLAY INVISIBLE (-2975 3425);
FORCEPROP 1 LAST HDL_TAP TRUE
J 0
(-2650 3250);
DISPLAY 1.446809 (-2650 3250);
PAINT GREEN (-2650 3250);
DISPLAY INVISIBLE (-2650 3250);
FORCEPROP 1 LAST PATH I79
J 0
(-2977 3375);
DISPLAY 0.872340 (-2977 3375);
PAINT GREEN (-2977 3375);
DISPLAY INVISIBLE (-2977 3375);
FORCEADD TAP..1
(-2975 3475);
FORCEPROP 3 LASTPIN (-3025 3475) SIG_NAME UPI_CPU0_CPU1_P1P1_DP<2>
J 0
(-3015 3485);
DISPLAY 0.659574 (-3015 3485);
PAINT MONO (-3015 3485);
DISPLAY INVISIBLE (-3015 3485);
FORCEPROP 1 LASTPIN (-3025 3475) BN 2
J 0
(-3037 3483);
DISPLAY 0.617021 (-3037 3483);
PAINT PINK (-3037 3483);
FORCEPROP 2 LAST CDS_LIB mstr_standard
J 0
(-2975 3475);
PAINT MONO (-2975 3475);
DISPLAY INVISIBLE (-2975 3475);
FORCEPROP 1 LAST BODY_TYPE PLUMBING
J 0
(-2975 3525);
DISPLAY 1.446809 (-2975 3525);
PAINT GREEN (-2975 3525);
DISPLAY INVISIBLE (-2975 3525);
FORCEPROP 1 LAST HDL_TAP TRUE
J 0
(-2650 3350);
DISPLAY 1.446809 (-2650 3350);
PAINT GREEN (-2650 3350);
DISPLAY INVISIBLE (-2650 3350);
FORCEPROP 1 LAST PATH I80
J 0
(-2977 3475);
DISPLAY 0.872340 (-2977 3475);
PAINT GREEN (-2977 3475);
DISPLAY INVISIBLE (-2977 3475);
FORCEADD TAP..1
(-2975 3425);
FORCEPROP 3 LASTPIN (-3025 3425) SIG_NAME UPI_CPU0_CPU1_P1P1_DP<3>
J 0
(-3015 3435);
DISPLAY 0.659574 (-3015 3435);
PAINT MONO (-3015 3435);
DISPLAY INVISIBLE (-3015 3435);
FORCEPROP 1 LASTPIN (-3025 3425) BN 3
J 0
(-3037 3433);
DISPLAY 0.617021 (-3037 3433);
PAINT PINK (-3037 3433);
FORCEPROP 2 LAST CDS_LIB mstr_standard
J 0
(-2975 3425);
PAINT MONO (-2975 3425);
DISPLAY INVISIBLE (-2975 3425);
FORCEPROP 1 LAST BODY_TYPE PLUMBING
J 0
(-2975 3475);
DISPLAY 1.446809 (-2975 3475);
PAINT GREEN (-2975 3475);
DISPLAY INVISIBLE (-2975 3475);
FORCEPROP 1 LAST HDL_TAP TRUE
J 0
(-2650 3300);
DISPLAY 1.446809 (-2650 3300);
PAINT GREEN (-2650 3300);
DISPLAY INVISIBLE (-2650 3300);
FORCEPROP 1 LAST PATH I81
J 0
(-2977 3425);
DISPLAY 0.872340 (-2977 3425);
PAINT GREEN (-2977 3425);
DISPLAY INVISIBLE (-2977 3425);
FORCEADD TAP..1
(-2975 3525);
FORCEPROP 3 LASTPIN (-3025 3525) SIG_NAME UPI_CPU0_CPU1_P1P1_DP<1>
J 0
(-3015 3535);
DISPLAY 0.659574 (-3015 3535);
PAINT MONO (-3015 3535);
DISPLAY INVISIBLE (-3015 3535);
FORCEPROP 1 LASTPIN (-3025 3525) BN 1
J 0
(-3037 3533);
DISPLAY 0.617021 (-3037 3533);
PAINT PINK (-3037 3533);
FORCEPROP 2 LAST CDS_LIB mstr_standard
J 0
(-2975 3525);
PAINT MONO (-2975 3525);
DISPLAY INVISIBLE (-2975 3525);
FORCEPROP 1 LAST BODY_TYPE PLUMBING
J 0
(-2975 3575);
DISPLAY 1.446809 (-2975 3575);
PAINT GREEN (-2975 3575);
DISPLAY INVISIBLE (-2975 3575);
FORCEPROP 1 LAST HDL_TAP TRUE
J 0
(-2650 3400);
DISPLAY 1.446809 (-2650 3400);
PAINT GREEN (-2650 3400);
DISPLAY INVISIBLE (-2650 3400);
FORCEPROP 1 LAST PATH I82
J 0
(-2977 3525);
DISPLAY 0.872340 (-2977 3525);
PAINT GREEN (-2977 3525);
DISPLAY INVISIBLE (-2977 3525);
FORCEADD TAP..1
(-2975 3575);
FORCEPROP 3 LASTPIN (-3025 3575) SIG_NAME UPI_CPU0_CPU1_P1P1_DP<0>
J 0
(-3015 3585);
DISPLAY 0.659574 (-3015 3585);
PAINT MONO (-3015 3585);
DISPLAY INVISIBLE (-3015 3585);
FORCEPROP 1 LASTPIN (-3025 3575) BN 0
J 0
(-3037 3583);
DISPLAY 0.617021 (-3037 3583);
PAINT PINK (-3037 3583);
FORCEPROP 2 LAST CDS_LIB mstr_standard
J 2
(-2975 3575);
PAINT MONO (-2975 3575);
DISPLAY INVISIBLE (-2975 3575);
FORCEPROP 1 LAST BODY_TYPE PLUMBING
J 0
(-2975 3625);
DISPLAY 1.446809 (-2975 3625);
PAINT GREEN (-2975 3625);
DISPLAY INVISIBLE (-2975 3625);
FORCEPROP 1 LAST HDL_TAP TRUE
J 0
(-2650 3450);
DISPLAY 1.446809 (-2650 3450);
PAINT GREEN (-2650 3450);
DISPLAY INVISIBLE (-2650 3450);
FORCEPROP 1 LAST PATH I83
J 0
(-2977 3575);
DISPLAY 0.872340 (-2977 3575);
PAINT GREEN (-2977 3575);
DISPLAY INVISIBLE (-2977 3575);
FORCEADD OFFPAGE..2
(-1775 2575);
FORCEPROP 2 LAST $XR0 68 
J 0
(-1586 2575);
DISPLAY 0.638298 (-1586 2575);
PAINT MONO (-1586 2575);
FORCEPROP 2 LAST CDS_LIB mstr_standard
J 0
(-1775 2575);
PAINT MONO (-1775 2575);
DISPLAY INVISIBLE (-1775 2575);
FORCEPROP 1 LAST OFFPAGE TRUE
J 0
(-1450 2450);
DISPLAY 1.170213 (-1450 2450);
PAINT GREEN (-1450 2450);
DISPLAY INVISIBLE (-1450 2450);
FORCEPROP 1 LAST COMMENT_BODY TRUE
J 0
(-1820 2480);
DISPLAY 1.170213 (-1820 2480);
PAINT GREEN (-1820 2480);
DISPLAY INVISIBLE (-1820 2480);
FORCEPROP 2 LAST PATH I84
J 0
(-1600 2650);
DISPLAY 1.021277 (-1600 2650);
PAINT ORANGE (-1600 2650);
DISPLAY INVISIBLE (-1600 2650);
FORCEADD OFFPAGE..2
(-1775 3625);
FORCEPROP 2 LAST $XR0 68 
J 0
(-1586 3625);
DISPLAY 0.638298 (-1586 3625);
PAINT MONO (-1586 3625);
FORCEPROP 2 LAST CDS_LIB mstr_standard
J 0
(-1775 3625);
PAINT MONO (-1775 3625);
DISPLAY INVISIBLE (-1775 3625);
FORCEPROP 1 LAST OFFPAGE TRUE
J 0
(-1450 3500);
DISPLAY 1.170213 (-1450 3500);
PAINT GREEN (-1450 3500);
DISPLAY INVISIBLE (-1450 3500);
FORCEPROP 1 LAST COMMENT_BODY TRUE
J 0
(-1820 3530);
DISPLAY 1.170213 (-1820 3530);
PAINT GREEN (-1820 3530);
DISPLAY INVISIBLE (-1820 3530);
FORCEPROP 2 LAST PATH I85
J 0
(-1600 3700);
DISPLAY 1.021277 (-1600 3700);
PAINT ORANGE (-1600 3700);
DISPLAY INVISIBLE (-1600 3700);
FORCEADD SKX_EXT_B..14
(-4100 2575);
FORCEPROP 2 LASTPIN (-3300 3125) $PN G12
J 0
(-3290 3135);
DISPLAY 0.617021 (-3290 3135);
PAINT ORANGE (-3290 3135);
FORCEPROP 2 LASTPIN (-3300 2525) $PN H21
J 0
(-3290 2535);
DISPLAY 0.617021 (-3290 2535);
PAINT ORANGE (-3290 2535);
FORCEPROP 1 LAST LOCATION U5D1
J 0
(-4850 3825);
DISPLAY 0.617021 (-4850 3825);
PAINT AQUA (-4850 3825);
FORCEPROP 1 LAST PART_NUMBER TBD
J 0
(-4850 1375);
DISPLAY 0.617021 (-4850 1375);
PAINT BLUE (-4850 1375);
FORCEPROP 1 LAST MATERIAL IC
J 0
(-4850 3775);
DISPLAY 0.617021 (-4850 3775);
PAINT SKYBLUE (-4850 3775);
FORCEPROP 2 LASTPIN (-3300 3575) $PN K21
J 0
(-3290 3585);
DISPLAY 0.617021 (-3290 3585);
PAINT ORANGE (-3290 3585);
FORCEPROP 2 LASTPIN (-3300 3525) $PN G20
J 0
(-3290 3535);
DISPLAY 0.617021 (-3290 3535);
PAINT ORANGE (-3290 3535);
FORCEPROP 2 LASTPIN (-3300 3475) $PN H19
J 0
(-3290 3485);
DISPLAY 0.617021 (-3290 3485);
PAINT ORANGE (-3290 3485);
FORCEPROP 2 LASTPIN (-3300 3425) $PN J18
J 0
(-3290 3435);
DISPLAY 0.617021 (-3290 3435);
PAINT ORANGE (-3290 3435);
FORCEPROP 2 LASTPIN (-3300 3375) $PN L18
J 0
(-3290 3385);
DISPLAY 0.617021 (-3290 3385);
PAINT ORANGE (-3290 3385);
FORCEPROP 2 LASTPIN (-3300 3325) $PN G16
J 0
(-3290 3335);
DISPLAY 0.617021 (-3290 3335);
PAINT ORANGE (-3290 3335);
FORCEPROP 2 LASTPIN (-3300 3275) $PN H15
J 0
(-3290 3285);
DISPLAY 0.617021 (-3290 3285);
PAINT ORANGE (-3290 3285);
FORCEPROP 2 LASTPIN (-3300 3225) $PN E14
J 0
(-3290 3235);
DISPLAY 0.617021 (-3290 3235);
PAINT ORANGE (-3290 3235);
FORCEPROP 2 LASTPIN (-3300 3175) $PN F13
J 0
(-3290 3185);
DISPLAY 0.617021 (-3290 3185);
PAINT ORANGE (-3290 3185);
FORCEPROP 2 LASTPIN (-3300 3075) $PN H9
J 0
(-3290 3085);
DISPLAY 0.617021 (-3290 3085);
PAINT ORANGE (-3290 3085);
FORCEPROP 2 LASTPIN (-3300 3025) $PN E10
J 0
(-3290 3035);
DISPLAY 0.617021 (-3290 3035);
PAINT ORANGE (-3290 3035);
FORCEPROP 2 LASTPIN (-3300 2975) $PN F9
J 0
(-3290 2985);
DISPLAY 0.617021 (-3290 2985);
PAINT ORANGE (-3290 2985);
FORCEPROP 2 LASTPIN (-3300 2925) $PN J8
J 0
(-3290 2935);
DISPLAY 0.617021 (-3290 2935);
PAINT ORANGE (-3290 2935);
FORCEPROP 2 LASTPIN (-3300 2875) $PN K7
J 0
(-3290 2885);
DISPLAY 0.617021 (-3290 2885);
PAINT ORANGE (-3290 2885);
FORCEPROP 2 LASTPIN (-3300 2825) $PN F7
J 0
(-3290 2835);
DISPLAY 0.617021 (-3290 2835);
PAINT ORANGE (-3290 2835);
FORCEPROP 2 LASTPIN (-3300 2775) $PN H5
J 0
(-3290 2785);
DISPLAY 0.617021 (-3290 2785);
PAINT ORANGE (-3290 2785);
FORCEPROP 2 LASTPIN (-3300 2725) $PN M5
J 0
(-3290 2735);
DISPLAY 0.617021 (-3290 2735);
PAINT ORANGE (-3290 2735);
FORCEPROP 2 LASTPIN (-3300 2675) $PN K3
J 0
(-3290 2685);
DISPLAY 0.617021 (-3290 2685);
PAINT ORANGE (-3290 2685);
FORCEPROP 2 LASTPIN (-3300 2625) $PN P3
J 0
(-3290 2635);
DISPLAY 0.617021 (-3290 2635);
PAINT ORANGE (-3290 2635);
FORCEPROP 2 LASTPIN (-3300 2475) $PN F21
J 0
(-3290 2485);
DISPLAY 0.617021 (-3290 2485);
PAINT ORANGE (-3290 2485);
FORCEPROP 2 LASTPIN (-3300 2425) $PN J20
J 0
(-3290 2435);
DISPLAY 0.617021 (-3290 2435);
PAINT ORANGE (-3290 2435);
FORCEPROP 2 LASTPIN (-3300 2375) $PN G18
J 0
(-3290 2385);
DISPLAY 0.617021 (-3290 2385);
PAINT ORANGE (-3290 2385);
FORCEPROP 2 LASTPIN (-3300 2325) $PN K19
J 0
(-3290 2335);
DISPLAY 0.617021 (-3290 2335);
PAINT ORANGE (-3290 2335);
FORCEPROP 2 LASTPIN (-3300 2275) $PN H17
J 0
(-3290 2285);
DISPLAY 0.617021 (-3290 2285);
PAINT ORANGE (-3290 2285);
FORCEPROP 2 LASTPIN (-3300 2225) $PN F15
J 0
(-3290 2235);
DISPLAY 0.617021 (-3290 2235);
PAINT ORANGE (-3290 2235);
FORCEPROP 2 LASTPIN (-3300 2175) $PN D15
J 0
(-3290 2185);
DISPLAY 0.617021 (-3290 2185);
PAINT ORANGE (-3290 2185);
FORCEPROP 2 LASTPIN (-3300 2125) $PN G14
J 0
(-3290 2135);
DISPLAY 0.617021 (-3290 2135);
PAINT ORANGE (-3290 2135);
FORCEPROP 2 LASTPIN (-3300 2075) $PN E12
J 0
(-3290 2085);
DISPLAY 0.617021 (-3290 2085);
PAINT ORANGE (-3290 2085);
FORCEPROP 2 LASTPIN (-3300 2025) $PN G10
J 0
(-3290 2035);
DISPLAY 0.617021 (-3290 2035);
PAINT ORANGE (-3290 2035);
FORCEPROP 2 LASTPIN (-3300 1975) $PN F11
J 0
(-3290 1985);
DISPLAY 0.617021 (-3290 1985);
PAINT ORANGE (-3290 1985);
FORCEPROP 2 LASTPIN (-3300 1925) $PN D9
J 0
(-3290 1935);
DISPLAY 0.617021 (-3290 1935);
PAINT ORANGE (-3290 1935);
FORCEPROP 2 LASTPIN (-3300 1875) $PN K9
J 0
(-3290 1885);
DISPLAY 0.617021 (-3290 1885);
PAINT ORANGE (-3290 1885);
FORCEPROP 2 LASTPIN (-3300 1825) $PN H7
J 0
(-3290 1835);
DISPLAY 0.617021 (-3290 1835);
PAINT ORANGE (-3290 1835);
FORCEPROP 2 LASTPIN (-3300 1775) $PN G6
J 0
(-3290 1785);
DISPLAY 0.617021 (-3290 1785);
PAINT ORANGE (-3290 1785);
FORCEPROP 2 LASTPIN (-3300 1725) $PN J6
J 0
(-3290 1735);
DISPLAY 0.617021 (-3290 1735);
PAINT ORANGE (-3290 1735);
FORCEPROP 2 LASTPIN (-3300 1675) $PN K5
J 0
(-3290 1685);
DISPLAY 0.617021 (-3290 1685);
PAINT ORANGE (-3290 1685);
FORCEPROP 2 LASTPIN (-3300 1625) $PN L4
J 0
(-3290 1635);
DISPLAY 0.617021 (-3290 1635);
PAINT ORANGE (-3290 1635);
FORCEPROP 2 LASTPIN (-3300 1575) $PN M3
J 0
(-3290 1585);
DISPLAY 0.617021 (-3290 1585);
PAINT ORANGE (-3290 1585);
FORCEPROP 2 LASTPIN (-4900 3575) $PN AA20
J 2
(-4910 3585);
DISPLAY 0.617021 (-4910 3585);
PAINT ORANGE (-4910 3585);
FORCEPROP 2 LASTPIN (-4900 3525) $PN W20
J 2
(-4910 3535);
DISPLAY 0.617021 (-4910 3535);
PAINT ORANGE (-4910 3535);
FORCEPROP 2 LASTPIN (-4900 3475) $PN Y19
J 2
(-4910 3485);
DISPLAY 0.617021 (-4910 3485);
PAINT ORANGE (-4910 3485);
FORCEPROP 2 LASTPIN (-4900 3425) $PN T21
J 2
(-4910 3435);
DISPLAY 0.617021 (-4910 3435);
PAINT ORANGE (-4910 3435);
FORCEPROP 2 LASTPIN (-4900 3375) $PN T19
J 2
(-4910 3385);
DISPLAY 0.617021 (-4910 3385);
PAINT ORANGE (-4910 3385);
FORCEPROP 2 LASTPIN (-4900 3325) $PN P19
J 2
(-4910 3335);
DISPLAY 0.617021 (-4910 3335);
PAINT ORANGE (-4910 3335);
FORCEPROP 2 LASTPIN (-4900 3275) $PN V17
J 2
(-4910 3285);
DISPLAY 0.617021 (-4910 3285);
PAINT ORANGE (-4910 3285);
FORCEPROP 2 LASTPIN (-4900 3225) $PN W16
J 2
(-4910 3235);
DISPLAY 0.617021 (-4910 3235);
PAINT ORANGE (-4910 3235);
FORCEPROP 2 LASTPIN (-4900 3175) $PN N16
J 2
(-4910 3185);
DISPLAY 0.617021 (-4910 3185);
PAINT ORANGE (-4910 3185);
FORCEPROP 2 LASTPIN (-4900 3125) $PN T15
J 2
(-4910 3135);
DISPLAY 0.617021 (-4910 3135);
PAINT ORANGE (-4910 3135);
FORCEPROP 2 LASTPIN (-4900 3025) $PN M13
J 2
(-4910 3035);
DISPLAY 0.617021 (-4910 3035);
PAINT ORANGE (-4910 3035);
FORCEPROP 2 LASTPIN (-4900 2975) $PN N12
J 2
(-4910 2985);
DISPLAY 0.617021 (-4910 2985);
PAINT ORANGE (-4910 2985);
FORCEPROP 2 LASTPIN (-4900 2925) $PN T11
J 2
(-4910 2935);
DISPLAY 0.617021 (-4910 2935);
PAINT ORANGE (-4910 2935);
FORCEPROP 2 LASTPIN (-4900 2875) $PN U10
J 2
(-4910 2885);
DISPLAY 0.617021 (-4910 2885);
PAINT ORANGE (-4910 2885);
FORCEPROP 2 LASTPIN (-4900 2825) $PN N10
J 2
(-4910 2835);
DISPLAY 0.617021 (-4910 2835);
PAINT ORANGE (-4910 2835);
FORCEPROP 2 LASTPIN (-4900 2775) $PN R8
J 2
(-4910 2785);
DISPLAY 0.617021 (-4910 2785);
PAINT ORANGE (-4910 2785);
FORCEPROP 2 LASTPIN (-4900 2725) $PN U8
J 2
(-4910 2735);
DISPLAY 0.617021 (-4910 2735);
PAINT ORANGE (-4910 2735);
FORCEPROP 2 LASTPIN (-4900 2675) $PN T7
J 2
(-4910 2685);
DISPLAY 0.617021 (-4910 2685);
PAINT ORANGE (-4910 2685);
FORCEPROP 2 LASTPIN (-4900 2625) $PN R6
J 2
(-4910 2635);
DISPLAY 0.617021 (-4910 2635);
PAINT ORANGE (-4910 2635);
FORCEPROP 2 LASTPIN (-4900 2525) $PN AB19
J 2
(-4910 2535);
DISPLAY 0.617021 (-4910 2535);
PAINT ORANGE (-4910 2535);
FORCEPROP 2 LASTPIN (-4900 2475) $PN Y21
J 2
(-4910 2485);
DISPLAY 0.617021 (-4910 2485);
PAINT ORANGE (-4910 2485);
FORCEPROP 2 LASTPIN (-4900 2425) $PN V19
J 2
(-4910 2435);
DISPLAY 0.617021 (-4910 2435);
PAINT ORANGE (-4910 2435);
FORCEPROP 2 LASTPIN (-4900 2375) $PN P21
J 2
(-4910 2385);
DISPLAY 0.617021 (-4910 2385);
PAINT ORANGE (-4910 2385);
FORCEPROP 2 LASTPIN (-4900 2325) $PN U18
J 2
(-4910 2335);
DISPLAY 0.617021 (-4910 2335);
PAINT ORANGE (-4910 2335);
FORCEPROP 2 LASTPIN (-4900 2275) $PN R20
J 2
(-4910 2285);
DISPLAY 0.617021 (-4910 2285);
PAINT ORANGE (-4910 2285);
FORCEPROP 2 LASTPIN (-4900 2225) $PN W18
J 2
(-4910 2235);
DISPLAY 0.617021 (-4910 2235);
PAINT ORANGE (-4910 2235);
FORCEPROP 2 LASTPIN (-4900 2175) $PN U16
J 2
(-4910 2185);
DISPLAY 0.617021 (-4910 2185);
PAINT ORANGE (-4910 2185);
FORCEPROP 2 LASTPIN (-4900 2125) $PN P17
J 2
(-4910 2135);
DISPLAY 0.617021 (-4910 2135);
PAINT ORANGE (-4910 2135);
FORCEPROP 2 LASTPIN (-4900 2075) $PN R16
J 2
(-4910 2085);
DISPLAY 0.617021 (-4910 2085);
PAINT ORANGE (-4910 2085);
FORCEPROP 2 LASTPIN (-4900 2025) $PN R12
J 2
(-4910 2035);
DISPLAY 0.617021 (-4910 2035);
PAINT ORANGE (-4910 2035);
FORCEPROP 2 LASTPIN (-4900 1975) $PN N14
J 2
(-4910 1985);
DISPLAY 0.617021 (-4910 1985);
PAINT ORANGE (-4910 1985);
FORCEPROP 2 LASTPIN (-4900 1925) $PN L12
J 2
(-4910 1935);
DISPLAY 0.617021 (-4910 1935);
PAINT ORANGE (-4910 1935);
FORCEPROP 2 LASTPIN (-4900 1875) $PN U12
J 2
(-4910 1885);
DISPLAY 0.617021 (-4910 1885);
PAINT ORANGE (-4910 1885);
FORCEPROP 2 LASTPIN (-4900 1825) $PN R10
J 2
(-4910 1835);
DISPLAY 0.617021 (-4910 1835);
PAINT ORANGE (-4910 1835);
FORCEPROP 2 LASTPIN (-4900 1775) $PN P9
J 2
(-4910 1785);
DISPLAY 0.617021 (-4910 1785);
PAINT ORANGE (-4910 1785);
FORCEPROP 2 LASTPIN (-4900 1725) $PN T9
J 2
(-4910 1735);
DISPLAY 0.617021 (-4910 1735);
PAINT ORANGE (-4910 1735);
FORCEPROP 2 LASTPIN (-4900 1675) $PN V7
J 2
(-4910 1685);
DISPLAY 0.617021 (-4910 1685);
PAINT ORANGE (-4910 1685);
FORCEPROP 2 LASTPIN (-4900 1625) $PN P7
J 2
(-4910 1635);
DISPLAY 0.617021 (-4910 1635);
PAINT ORANGE (-4910 1635);
FORCEPROP 2 LASTPIN (-4900 1575) $PN T5
J 2
(-4910 1585);
DISPLAY 0.617021 (-4910 1585);
PAINT ORANGE (-4910 1585);
FORCEPROP 2 LASTPIN (-4900 3075) $PN P13
J 2
(-4910 3085);
DISPLAY 0.617021 (-4910 3085);
PAINT ORANGE (-4910 3085);
FORCEPROP 1 LAST PACK_TYPE BGA1
J 0
(-4850 3875);
PAINT SKYBLUE (-4850 3875);
DISPLAY INVISIBLE (-4850 3875);
FORCEPROP 2 LAST CDS_LIB chpset_lib
J 0
(-4100 2575);
PAINT ORANGE (-4100 2575);
DISPLAY INVISIBLE (-4100 2575);
FORCEPROP 2 LAST SEC_TYPE BGA1
J 0
(-4850 3875);
DISPLAY 1.021277 (-4850 3875);
PAINT ORANGE (-4850 3875);
DISPLAY INVISIBLE (-4850 3875);
FORCEPROP 2 LAST SEC 14
J 0
(-4850 3875);
DISPLAY 0.680851 (-4850 3875);
PAINT MONO (-4850 3875);
DISPLAY INVISIBLE (-4850 3875);
FORCEPROP 2 LAST CDS_LOCATION U5D1
J 0
(-4850 3825);
DISPLAY 0.617021 (-4850 3825);
PAINT AQUA (-4850 3825);
DISPLAY INVISIBLE (-4850 3825);
FORCEPROP 1 LAST PATH I86
J 0
(-4100 3775);
PAINT GREEN (-4100 3775);
DISPLAY INVISIBLE (-4100 3775);
FORCEPROP 0 LAST ROOM CPU0
J 0
(-4850 3925);
DISPLAY 1.021277 (-4850 3925);
PAINT ORANGE (-4850 3925);
DISPLAY INVISIBLE (-4850 3925);
FORCEADD TAP..1
R 2
(-5300 1875);
FORCEPROP 3 LASTPIN (-5250 1875) SIG_NAME UPI_CPU1_CPU0_P1P1_DN<13>
J 0
(-5240 1885);
DISPLAY 0.659574 (-5240 1885);
PAINT MONO (-5240 1885);
DISPLAY INVISIBLE (-5240 1885);
FORCEPROP 1 LASTPIN (-5250 1875) BN 13
J 2
(-5238 1883);
DISPLAY 0.617021 (-5238 1883);
PAINT PINK (-5238 1883);
FORCEPROP 2 LAST CDS_LIB mstr_standard
J 0
(-5300 1875);
PAINT MONO (-5300 1875);
DISPLAY INVISIBLE (-5300 1875);
FORCEPROP 1 LAST BODY_TYPE PLUMBING
J 2
(-5300 1925);
DISPLAY 1.446809 (-5300 1925);
PAINT GREEN (-5300 1925);
DISPLAY INVISIBLE (-5300 1925);
FORCEPROP 1 LAST HDL_TAP TRUE
J 2
(-5625 1750);
DISPLAY 1.446809 (-5625 1750);
PAINT GREEN (-5625 1750);
DISPLAY INVISIBLE (-5625 1750);
FORCEPROP 1 LAST PATH I9
J 2
(-5298 1875);
DISPLAY 0.872340 (-5298 1875);
PAINT GREEN (-5298 1875);
DISPLAY INVISIBLE (-5298 1875);
FORCEADD PRELIM..10
(-4115 2565);
PAINT GRAY (-4115 2565);
FORCEPROP 2 LAST CDS_LIB mstr_misc
J 0
(-4115 2565);
PAINT ORANGE (-4115 2565);
DISPLAY INVISIBLE (-4115 2565);
FORCEPROP 1 LAST COMMENT_BODY TRUE
J 0
(-4115 2565);
PAINT ORANGE (-4115 2565);
DISPLAY INVISIBLE (-4115 2565);
FORCEADD INTEL_CORP_BPAGE..1
(0 0);
FORCEPROP 1 LAST CDS_CON_LAST_MODIFIED Fri Jun 16 17:48:13 2017
J 0
(-1425 325);
DISPLAY 1.340426 (-1425 325);
PAINT GREEN (-1425 325);
DISPLAY INVISIBLE (-1425 325);
FORCEPROP 1 LAST CUSTOM_TXT_CDS <CURRENT_DESIGN_SHEET> OF <TOTAL_DESIGN_SHEETS>
J 0
(-500 25);
PAINT ORANGE (-500 25);
FORCEPROP 1 LAST CUSTOM_TXT_CDS <CON_LAST_MODIFIED>
J 0
(-4000 100);
PAINT ORANGE (-4000 100);
FORCEPROP 2 LAST CUSTOM_TXT_CDS <XR_PAGE_TITLE>
J 0
(-7890 5250);
DISPLAY 0.638298 (-7890 5250);
PAINT PINK (-7890 5250);
DISPLAY INVISIBLE (-7890 5250);
FORCEPROP 1 LAST SCH_TITLE SKYLAKE - SKT0 - 14 OF 21
J 0
(-7950 50);
DISPLAY 1.212766 (-7950 50);
PAINT GREEN (-7950 50);
FORCEPROP 2 LAST PAGE_BORDER TRUE
J 0
(-7890 5250);
DISPLAY 0.851064 (-7890 5250);
PAINT PINK (-7890 5250);
DISPLAY INVISIBLE (-7890 5250);
FORCEPROP 2 LAST CDS_LIB mstr_symbols
J 0
(0 0);
PAINT ORANGE (0 0);
DISPLAY INVISIBLE (0 0);
FORCEPROP 1 LAST COMMENT_BODY TRUE
J 0
(12 12);
DISPLAY 0.638298 (12 12);
PAINT GREEN (12 12);
DISPLAY INVISIBLE (12 12);
FORCEPROP 2 LAST CDS_XR_PAGE_TITLE CR-34 : @BASEBOARD_FAB2_LIB.BASEBOARD_FAB2(SCH_1):PAGE34
J 0
(-7890 5250);
DISPLAY 0.638298 (-7890 5250);
PAINT PINK (-7890 5250);
DISPLAY INVISIBLE (-7890 5250);
FORCEADD DESIGN_NOTE..1
(-4675 1300);
FORCEPROP 0 LAST L1 CPU SYMBOLS 1-30 ARE PRELIMINARY AND SUBJECT TO CHANGE
J 0
(-4875 1175);
DISPLAY 1.021277 (-4875 1175);
PAINT ORANGE (-4875 1175);
FORCEPROP 2 LAST CDS_LIB mstr_symbols
J 0
(-4675 1300);
PAINT ORANGE (-4675 1300);
DISPLAY INVISIBLE (-4675 1300);
FORCEPROP 1 LAST COMMENT_BODY TRUE
J 0
(-4650 1400);
DISPLAY 0.978723 (-4650 1400);
PAINT ORANGE (-4650 1400);
DISPLAY INVISIBLE (-4650 1400);
WIRE 17 -1 (-2925 1650)(-2925 1600);
WIRE 17 -1 (-2925 1700)(-2925 1650);
WIRE 17 -1 (-2925 1750)(-2925 1700);
WIRE 17 -1 (-2925 1800)(-2925 1750);
WIRE 17 -1 (-2925 1850)(-2925 1800);
WIRE 17 -1 (-2925 1900)(-2925 1850);
WIRE 17 -1 (-2925 1950)(-2925 1900);
WIRE 17 -1 (-2925 2000)(-2925 1950);
WIRE 17 -1 (-2925 2050)(-2925 2000);
WIRE 17 -1 (-2925 2100)(-2925 2050);
WIRE 17 -1 (-2925 2150)(-2925 2100);
WIRE 17 -1 (-2925 2200)(-2925 2150);
WIRE 17 -1 (-2925 2250)(-2925 2200);
WIRE 17 -1 (-2925 2300)(-2925 2250);
WIRE 17 -1 (-2925 2350)(-2925 2300);
WIRE 17 -1 (-2925 2400)(-2925 2350);
WIRE 17 -1 (-2925 2450)(-2925 2400);
WIRE 17 -1 (-2925 2500)(-2925 2450);
WIRE 17 -1 (-2925 2550)(-2925 2500);
WIRE 17 -1 (-2925 2575)(-1825 2575);
FORCEPROP 2 LAST SIG_NAME UPI_CPU0_CPU1_P1P1_DN<19..0>
J 0
(-2835 2585);
DISPLAY 0.617021 (-2835 2585);
PAINT ORANGE (-2835 2585);
WIRE 17 -1 (-2925 2575)(-2925 2550);
WIRE 17 -1 (-2925 2700)(-2925 2650);
WIRE 17 -1 (-2925 2750)(-2925 2700);
WIRE 17 -1 (-2925 2800)(-2925 2750);
WIRE 17 -1 (-2925 2850)(-2925 2800);
WIRE 17 -1 (-2925 2900)(-2925 2850);
WIRE 17 -1 (-2925 2950)(-2925 2900);
WIRE 17 -1 (-2925 3000)(-2925 2950);
WIRE 17 -1 (-2925 3050)(-2925 3000);
WIRE 17 -1 (-2925 3100)(-2925 3050);
WIRE 17 -1 (-2925 3150)(-2925 3100);
WIRE 17 -1 (-2925 3200)(-2925 3150);
WIRE 17 -1 (-2925 3250)(-2925 3200);
WIRE 17 -1 (-2925 3300)(-2925 3250);
WIRE 17 -1 (-2925 3350)(-2925 3300);
WIRE 17 -1 (-2925 3400)(-2925 3350);
WIRE 17 -1 (-2925 3450)(-2925 3400);
WIRE 17 -1 (-2925 3500)(-2925 3450);
WIRE 17 -1 (-2925 3550)(-2925 3500);
WIRE 17 -1 (-2925 3600)(-2925 3550);
WIRE 17 -1 (-2925 3625)(-1825 3625);
FORCEPROP 2 LAST SIG_NAME UPI_CPU0_CPU1_P1P1_DP<19..0>
J 0
(-2835 3635);
DISPLAY 0.617021 (-2835 3635);
PAINT ORANGE (-2835 3635);
WIRE 17 -1 (-2925 3625)(-2925 3600);
WIRE 17 -1 (-5350 1600)(-5350 1650);
WIRE 17 -1 (-5350 1650)(-5350 1700);
WIRE 17 -1 (-5350 1750)(-5350 1700);
WIRE 17 -1 (-5350 1800)(-5350 1750);
WIRE 17 -1 (-5350 1850)(-5350 1800);
WIRE 17 -1 (-5350 1900)(-5350 1850);
WIRE 17 -1 (-5350 1950)(-5350 1900);
WIRE 17 -1 (-5350 2000)(-5350 1950);
WIRE 17 -1 (-5350 2050)(-5350 2000);
WIRE 17 -1 (-5350 2100)(-5350 2050);
WIRE 17 -1 (-5350 2150)(-5350 2100);
WIRE 17 -1 (-5350 2200)(-5350 2150);
WIRE 17 -1 (-5350 2250)(-5350 2200);
WIRE 17 -1 (-5350 2300)(-5350 2250);
WIRE 17 -1 (-5350 2350)(-5350 2300);
WIRE 17 -1 (-5350 2400)(-5350 2350);
WIRE 17 -1 (-5350 2450)(-5350 2400);
WIRE 17 -1 (-6450 2575)(-5350 2575);
FORCEPROP 2 LAST SIG_NAME UPI_CPU1_CPU0_P1P1_DN<19..0>
J 0
(-6385 2585);
DISPLAY 0.617021 (-6385 2585);
PAINT ORANGE (-6385 2585);
WIRE 17 -1 (-5350 2550)(-5350 2575);
WIRE 17 -1 (-5350 2450)(-5350 2500);
WIRE 17 -1 (-5350 2500)(-5350 2550);
WIRE 17 -1 (-5350 2650)(-5350 2700);
WIRE 17 -1 (-5350 2700)(-5350 2750);
WIRE 17 -1 (-5350 2800)(-5350 2750);
WIRE 17 -1 (-5350 2850)(-5350 2800);
WIRE 17 -1 (-5350 2900)(-5350 2850);
WIRE 17 -1 (-5350 2950)(-5350 2900);
WIRE 17 -1 (-5350 3000)(-5350 2950);
WIRE 17 -1 (-5350 3050)(-5350 3000);
WIRE 17 -1 (-5350 3100)(-5350 3050);
WIRE 17 -1 (-5350 3150)(-5350 3100);
WIRE 17 -1 (-5350 3200)(-5350 3150);
WIRE 17 -1 (-5350 3250)(-5350 3200);
WIRE 17 -1 (-5350 3300)(-5350 3250);
WIRE 17 -1 (-5350 3350)(-5350 3300);
WIRE 17 -1 (-5350 3400)(-5350 3350);
WIRE 17 -1 (-5350 3450)(-5350 3400);
WIRE 17 -1 (-5350 3500)(-5350 3450);
WIRE 17 -1 (-6450 3625)(-5350 3625);
FORCEPROP 2 LAST SIG_NAME UPI_CPU1_CPU0_P1P1_DP<19..0>
J 0
(-6360 3635);
DISPLAY 0.617021 (-6360 3635);
PAINT ORANGE (-6360 3635);
WIRE 17 -1 (-5350 3625)(-5350 3600);
WIRE 17 -1 (-5350 3500)(-5350 3550);
WIRE 17 -1 (-5350 3550)(-5350 3600);
WIRE 16 -1 (-5250 2925)(-4900 2925);
WIRE 16 -1 (-5250 3025)(-4900 3025);
WIRE 16 -1 (-3300 3025)(-3025 3025);
WIRE 16 -1 (-3025 3125)(-3300 3125);
WIRE 16 -1 (-3025 2975)(-3300 2975);
WIRE 16 -1 (-3025 2075)(-3300 2075);
WIRE 16 -1 (-3025 2225)(-3300 2225);
WIRE 16 -1 (-3025 2325)(-3300 2325);
WIRE 16 -1 (-3025 3425)(-3300 3425);
WIRE 16 -1 (-5250 2975)(-4900 2975);
WIRE 16 -1 (-5250 1575)(-4900 1575);
WIRE 16 -1 (-5250 1625)(-4900 1625);
WIRE 16 -1 (-5250 1675)(-4900 1675);
WIRE 16 -1 (-5250 1725)(-4900 1725);
WIRE 16 -1 (-5250 1775)(-4900 1775);
WIRE 16 -1 (-5250 1825)(-4900 1825);
WIRE 16 -1 (-5250 1875)(-4900 1875);
WIRE 16 -1 (-5250 1925)(-4900 1925);
WIRE 16 -1 (-5250 1975)(-4900 1975);
WIRE 16 -1 (-5250 2025)(-4900 2025);
WIRE 16 -1 (-5250 2625)(-4900 2625);
WIRE 16 -1 (-5250 2675)(-4900 2675);
WIRE 16 -1 (-5250 2725)(-4900 2725);
WIRE 16 -1 (-5250 2775)(-4900 2775);
WIRE 16 -1 (-5250 2825)(-4900 2825);
WIRE 16 -1 (-5250 2875)(-4900 2875);
WIRE 16 -1 (-5250 3075)(-4900 3075);
WIRE 16 -1 (-5250 3125)(-4900 3125);
WIRE 16 -1 (-5250 3175)(-4900 3175);
WIRE 16 -1 (-5250 3225)(-4900 3225);
WIRE 16 -1 (-5250 3275)(-4900 3275);
WIRE 16 -1 (-5250 3325)(-4900 3325);
WIRE 16 -1 (-5250 3375)(-4900 3375);
WIRE 16 -1 (-5250 3425)(-4900 3425);
WIRE 16 -1 (-5250 3475)(-4900 3475);
WIRE 16 -1 (-5250 3525)(-4900 3525);
WIRE 16 -1 (-5250 3575)(-4900 3575);
WIRE 16 -1 (-5250 2075)(-4900 2075);
WIRE 16 -1 (-5250 2125)(-4900 2125);
WIRE 16 -1 (-5250 2175)(-4900 2175);
WIRE 16 -1 (-5250 2225)(-4900 2225);
WIRE 16 -1 (-5250 2275)(-4900 2275);
WIRE 16 -1 (-5250 2325)(-4900 2325);
WIRE 16 -1 (-5250 2375)(-4900 2375);
WIRE 16 -1 (-5250 2425)(-4900 2425);
WIRE 16 -1 (-5250 2475)(-4900 2475);
WIRE 16 -1 (-5250 2525)(-4900 2525);
WIRE 16 -1 (-3025 1575)(-3300 1575);
WIRE 16 -1 (-3025 1625)(-3300 1625);
WIRE 16 -1 (-3025 1675)(-3300 1675);
WIRE 16 -1 (-3025 1725)(-3300 1725);
WIRE 16 -1 (-3300 1775)(-3025 1775);
WIRE 16 -1 (-3025 1825)(-3300 1825);
WIRE 16 -1 (-3300 1875)(-3025 1875);
WIRE 16 -1 (-3025 1925)(-3300 1925);
WIRE 16 -1 (-3025 1975)(-3300 1975);
WIRE 16 -1 (-3025 2025)(-3300 2025);
WIRE 16 -1 (-3025 2625)(-3300 2625);
WIRE 16 -1 (-3025 2675)(-3300 2675);
WIRE 16 -1 (-3300 2725)(-3025 2725);
WIRE 16 -1 (-3025 2775)(-3300 2775);
WIRE 16 -1 (-3025 2825)(-3300 2825);
WIRE 16 -1 (-3025 2875)(-3300 2875);
WIRE 16 -1 (-3025 2925)(-3300 2925);
WIRE 16 -1 (-3025 3075)(-3300 3075);
WIRE 16 -1 (-3025 3175)(-3300 3175);
WIRE 16 -1 (-3025 3225)(-3300 3225);
WIRE 16 -1 (-3025 3275)(-3300 3275);
WIRE 16 -1 (-3300 3325)(-3025 3325);
WIRE 16 -1 (-3300 3375)(-3025 3375);
WIRE 16 -1 (-3025 3475)(-3300 3475);
WIRE 16 -1 (-3025 3525)(-3300 3525);
WIRE 16 -1 (-3025 3575)(-3300 3575);
WIRE 16 -1 (-3300 2125)(-3025 2125);
WIRE 16 -1 (-3300 2175)(-3025 2175);
WIRE 16 -1 (-3025 2275)(-3300 2275);
WIRE 16 -1 (-3025 2375)(-3300 2375);
WIRE 16 -1 (-3025 2425)(-3300 2425);
WIRE 16 -1 (-3025 2475)(-3300 2475);
WIRE 16 -1 (-3025 2525)(-3300 2525);
FORCENOTE
BOM_COST=PROC_SOCKET
(-7925 250) 0;
DISPLAY LEFT (-7925 250);
DISPLAY 1.723404 (-7925 250);
PAINT PURPLE (-7925 250);
FORCENOTE
ROOM=CPU0
(-7925 375) 0;
DISPLAY LEFT (-7925 375);
DISPLAY 1.723404 (-7925 375);
PAINT PURPLE (-7925 375);
FORCENOTE
SKYLAKE - SKT0 - 14 OF 21
(-1700 175) 0;
DISPLAY LEFT (-1700 175);
DISPLAY 1.021277 (-1700 175);
PAINT RED (-1700 175);
QUIT
